FILE_TYPE = LIBRARY_PARTS;
{ Packager-XL run on 25-Aug-2023 AT 17:03:33 }
primitive '2N7002A7-2N7002A-7,SMLF,IC,BAMA';
  pin
    'G':
      PIN_NUMBER='(G)';
      INPUT_LOAD='(-0.01,0.01)';
      PINUSE='IN';
    'D':
      PIN_NUMBER='(D)';
      BIDIRECTIONAL='TRUE';
      INPUT_LOAD='(-0.01,0.01)';
      OUTPUT_LOAD='(1.0,-1.0)';
      PINUSE='BI';
    'S':
      PIN_NUMBER='(S)';
      BIDIRECTIONAL='TRUE';
      INPUT_LOAD='(-0.01,0.01)';
      OUTPUT_LOAD='(1.0,-1.0)';
      PINUSE='BI';
  end_pin;
  body
      PART_NAME='2N7002A7';
      BODY_NAME='2N7002A7';
      PHYS_DES_PREFIX='Q';
      CLASS='IC';
      STANDARD='';
      LIFECYCLE='';
      JEDEC_TYPE='SOT23_GDSXC';
      DESCRIPTION='TRANS MOS 2N7002A-7(60V,0.115A,0.25W)';
      MANUFTR='DDS';
      MANUF_PN='2N7002A-7';
      RD_CMPLS_LVL='EP(V1)';
      CMPLS_LVL='';
      DIP_SMD='';
      FP_ECN='';
      FROM_PJ='S1A-TONY';
      DATA='2N7002A.pdf';
      EE_CHECK_LIST='';
      STATUS='';
      PSL='';
      PREFERENCE='';
      CREATOR='';
      CREATEDAY='20140318';
      PARENT_PART_TYPE='2N7002A7';
      PARENT_PPT='2N7002A7';
      PARENT_PPT_PART='2N7002A7-2N7002A-7,SMLF,IC,BAM70020068';
  end_body;
end_primitive;
primitive '74HC1G126GW-74HC1G126GW,SMLF,IA';
  pin
    '2':
      PIN_NUMBER='(2)';
      INPUT_LOAD='(-0.01,0.01)';
      PINUSE='IN';
    '4':
      PIN_NUMBER='(4)';
      OUTPUT_TYPE='(TS,TS)';
      INPUT_LOAD='(-0.01,0.01)';
      OUTPUT_LOAD='(1.0,-1.0)';
      PINUSE='TRI';
    '5':
      PIN_NUMBER='(5)';
      PINUSE='POWER';
      NO_LOAD_CHECK='Both';
      NO_IO_CHECK='Both';
      NO_ASSERT_CHECK='TRUE';
      NO_DIR_CHECK='TRUE';
      ALLOW_CONNECT='TRUE';
    '1':
      PIN_NUMBER='(1)';
      INPUT_LOAD='(-0.01,0.01)';
      PINUSE='IN';
    'GND':
      PIN_NUMBER='(3)';
      PINUSE='POWER';
      NO_LOAD_CHECK='Both';
      NO_IO_CHECK='Both';
      NO_ASSERT_CHECK='TRUE';
      NO_DIR_CHECK='TRUE';
      ALLOW_CONNECT='TRUE';
  end_pin;
  body
      PART_NAME='74HC1G126GW';
      BODY_NAME='74HC1G126GW';
      PHYS_DES_PREFIX='U';
      CLASS='IC';
      STANDARD='';
      LIFECYCLE='';
      JEDEC_TYPE='TSSOP5_0-65_2-05X1-25';
      DESCRIPTION='IC(5P) 74HC1G126GW(SOT353)EP';
      MANUFTR='PHI';
      MANUF_PN='74HC1G126GW';
      RD_CMPLS_LVL='EP(V1)';
      CMPLS_LVL='EP(V1)';
      FROM_PJ='S2D-ANDY';
      DIP_SMD='';
      DATA='PHI_74HC1G126GW.pdf';
      EE_CHECK_LIST='';
      FP_ECN='';
      PSL='';
      CREATOR='';
      STATUS='';
      MSD='NA';
      ESD_CDM='NA';
      ESD_HBM='NA';
      ESD_MM='NA';
      PIN_LENGTH_SHORT_PIN='0 MILS';
      PIN_LENGTH_LONG_PIN='0 MILS';
      CREATEDAY='20100429';
      PARENT_PART_TYPE='74HC1G126GW';
      PARENT_PPT='74HC1G126GW';
      PARENT_PPT_PART='74HC1G126GW-74HC1G126GW,SMLF,IC,AL1G0126007';
  end_body;
end_primitive;
primitive '74LVC1G07GW-74LVC1G07GW,SMLF,EA';
  pin
    'VCC':
      PIN_NUMBER='(5)';
      PINUSE='POWER';
      NO_LOAD_CHECK='Both';
      NO_IO_CHECK='Both';
      NO_ASSERT_CHECK='TRUE';
      NO_DIR_CHECK='TRUE';
      ALLOW_CONNECT='TRUE';
    'A':
      PIN_NUMBER='(2)';
      INPUT_LOAD='(-0.01,0.01)';
      PINUSE='IN';
    'GND':
      PIN_NUMBER='(3)';
      PINUSE='POWER';
      NO_LOAD_CHECK='Both';
      NO_IO_CHECK='Both';
      NO_ASSERT_CHECK='TRUE';
      NO_DIR_CHECK='TRUE';
      ALLOW_CONNECT='TRUE';
    'Y':
      PIN_NUMBER='(4)';
      OUTPUT_TYPE='(OC,AND)';
      OUTPUT_LOAD='(1.0,*)';
      PINUSE='OCA';
    'NC':
      PIN_NUMBER='(1)';
      OUTPUT_TYPE='(TS,TS)';
      INPUT_LOAD='(-0.01,0.01)';
      OUTPUT_LOAD='(1.0,-1.0)';
      PINUSE='TRI';
  end_pin;
  body
      PART_NAME='74LVC1G07GW';
      BODY_NAME='74LVC1G07GW';
      PHYS_DES_PREFIX='U';
      CLASS='IC';
      JEDEC_TYPE='SOT353_Q';
      DESCRIPTION='IC(5P) 74LVC1G07GW(SOT353)';
      MANUFTR='PHI';
      MANUF_PN='74LVC1G07GW';
      RD_CMPLS_LVL='';
      CMPLS_LVL='EP';
      FROM_PJ='JS1-STEVEN';
      DIP_SMD='';
      DATA='PHI_74LVC1G07.pdf';
      EE_CHECK_LIST='';
      FP_ECN='';
      PSL='';
      LIFECYCLE='';
      CREATOR='';
      STANDARD='';
      CREATEDAY='20111207';
      STATUS='Normal';
      PARENT_PART_TYPE='74LVC1G07GW';
      PARENT_PPT='74LVC1G07GW';
      PARENT_PPT_PART='74LVC1G07GW-74LVC1G07GW,SMLF,EMPTY,ALVC1G07002';
  end_body;
end_primitive;
primitive '74LVC1G07GW-74LVC1G07GW,SMLF,IA';
  pin
    'VCC':
      PIN_NUMBER='(5)';
      PINUSE='POWER';
      NO_LOAD_CHECK='Both';
      NO_IO_CHECK='Both';
      NO_ASSERT_CHECK='TRUE';
      NO_DIR_CHECK='TRUE';
      ALLOW_CONNECT='TRUE';
    'A':
      PIN_NUMBER='(2)';
      INPUT_LOAD='(-0.01,0.01)';
      PINUSE='IN';
    'GND':
      PIN_NUMBER='(3)';
      PINUSE='POWER';
      NO_LOAD_CHECK='Both';
      NO_IO_CHECK='Both';
      NO_ASSERT_CHECK='TRUE';
      NO_DIR_CHECK='TRUE';
      ALLOW_CONNECT='TRUE';
    'Y':
      PIN_NUMBER='(4)';
      OUTPUT_TYPE='(OC,AND)';
      OUTPUT_LOAD='(1.0,*)';
      PINUSE='OCA';
    'NC':
      PIN_NUMBER='(1)';
      OUTPUT_TYPE='(TS,TS)';
      INPUT_LOAD='(-0.01,0.01)';
      OUTPUT_LOAD='(1.0,-1.0)';
      PINUSE='TRI';
  end_pin;
  body
      PART_NAME='74LVC1G07GW';
      BODY_NAME='74LVC1G07GW';
      PHYS_DES_PREFIX='U';
      CLASS='IC';
      JEDEC_TYPE='SOT353_Q';
      DESCRIPTION='IC(5P) 74LVC1G07GW(SOT353)';
      MANUFTR='PHI';
      MANUF_PN='74LVC1G07GW';
      RD_CMPLS_LVL='';
      CMPLS_LVL='EP';
      FROM_PJ='JS1-STEVEN';
      DIP_SMD='';
      DATA='PHI_74LVC1G07.pdf';
      EE_CHECK_LIST='';
      FP_ECN='';
      PSL='';
      LIFECYCLE='';
      CREATOR='';
      STANDARD='';
      CREATEDAY='20111207';
      STATUS='Normal';
      PARENT_PART_TYPE='74LVC1G07GW';
      PARENT_PPT='74LVC1G07GW';
      PARENT_PPT_PART='74LVC1G07GW-74LVC1G07GW,SMLF,IC,ALVC1G07002';
  end_body;
end_primitive;
primitive '74LVC1G07W57-74LVC1G07W5-7,SMLA';
  pin
    'VCC':
      PIN_NUMBER='(5)';
      PINUSE='POWER';
      NO_LOAD_CHECK='Both';
      NO_IO_CHECK='Both';
      NO_ASSERT_CHECK='TRUE';
      NO_DIR_CHECK='TRUE';
      ALLOW_CONNECT='TRUE';
    'A':
      PIN_NUMBER='(2)';
      INPUT_LOAD='(-0.01,0.01)';
      PINUSE='IN';
    'GND':
      PIN_NUMBER='(3)';
      PINUSE='POWER';
      NO_LOAD_CHECK='Both';
      NO_IO_CHECK='Both';
      NO_ASSERT_CHECK='TRUE';
      NO_DIR_CHECK='TRUE';
      ALLOW_CONNECT='TRUE';
    'Y':
      PIN_NUMBER='(4)';
      OUTPUT_TYPE='(OC,AND)';
      OUTPUT_LOAD='(1.0,*)';
      PINUSE='OCA';
    'NC1':
      PIN_NUMBER='(1)';
      OUTPUT_TYPE='(TS,TS)';
      INPUT_LOAD='(-0.01,0.01)';
      OUTPUT_LOAD='(1.0,-1.0)';
      PINUSE='TRI';
  end_pin;
  body
      PART_NAME='74LVC1G07W57';
      BODY_NAME='74LVC1G07W57';
      PHYS_DES_PREFIX='U';
      CLASS='IC';
      STANDARD='';
      LIFECYCLE='';
      JEDEC_TYPE='SOT25-5_0-95_3X1-6';
      DESCRIPTION='IC(5P)74LVC1G07W5-7(SOT25)';
      MANUFTR='DDS';
      MANUF_PN='74LVC1G07W5-7';
      RD_CMPLS_LVL='EP(V1)';
      CMPLS_LVL='';
      FROM_PJ='A5G-LEO';
      DIP_SMD='';
      DATA='DDS_74LVC1G07W5-7.pdf';
      EE_CHECK_LIST='';
      FP_ECN='';
      PSL='';
      CREATOR='';
      STATUS='';
      MSD='';
      ESD_CDM='';
      ESD_HBM='';
      ESD_MM='';
      PIN_LENGTH_SHORT_PIN='0 MILS';
      PIN_LENGTH_LONG_PIN='0 MILS';
      CREATEDAY='20210622';
      PARENT_PART_TYPE='74LVC1G07W57';
      PARENT_PPT='74LVC1G07W57';
      PARENT_PPT_PART='74LVC1G07W57-74LVC1G07W5-7,SMLF,IC,ALVC1G07001';
  end_body;
end_primitive;
primitive '74LVC1G08GW_SM-74LVC1G08GW,IC,A';
  pin
    'B':
      PIN_NUMBER='(1)';
      INPUT_LOAD='(-0.01,0.01)';
      OUTPUT_LOAD='(1.0,-1.0)';
      BIDIRECTIONAL='TRUE';
      PINUSE='BI';
    'A':
      PIN_NUMBER='(2)';
      INPUT_LOAD='(-0.01,0.01)';
      OUTPUT_LOAD='(1.0,-1.0)';
      BIDIRECTIONAL='TRUE';
      PINUSE='BI';
    'Y':
      PIN_NUMBER='(4)';
      INPUT_LOAD='(-0.01,0.01)';
      OUTPUT_LOAD='(1.0,-1.0)';
      BIDIRECTIONAL='TRUE';
      PINUSE='BI';
    'VCC':
      PIN_NUMBER='(5)';
      PINUSE='POWER';
    'GND':
      PIN_NUMBER='(3)';
      PINUSE='POWER';
  end_pin;
  body
      CLASS='IC';
      PART_NAME='74LVC1G08GW';
      PHYS_DES_PREFIX='U';
      STANDARD='End of Design';
      LIFECYCLE='Comp-Approve';
      ENVCOMP='YES';
      JEDEC_TYPE='SC70-5';
      DESCRIPTION='IC(5P) 74LVC1G08GW (SC70-5)';
      HEIGHT='.044IN';
      COMPONENT_TYPE='SMALLSMT';
      LEAD_LENGTH='';
      LPID='';
      DAY='20100711';
      PARENT_PART_TYPE='74LVC1G08GW';
      PARENT_PPT='74LVC1G08GW';
      PARENT_PPT_PART='74LVC1G08GW_SM-74LVC1G08GW,IC,ALVC1G08009';
  end_body;
end_primitive;
primitive '74LVC1G126SE7-74LVC1G126SE-7,SA';
  pin
    'A':
      PIN_NUMBER='(2)';
      INPUT_LOAD='(-0.01,0.01)';
      PINUSE='IN';
    'Y':
      PIN_NUMBER='(4)';
      OUTPUT_LOAD='(1.0,-1.0)';
      PINUSE='OUT';
    'VCC':
      PIN_NUMBER='(5)';
      PINUSE='POWER';
      NO_LOAD_CHECK='Both';
      NO_IO_CHECK='Both';
      NO_ASSERT_CHECK='TRUE';
      NO_DIR_CHECK='TRUE';
      ALLOW_CONNECT='TRUE';
    'GND':
      PIN_NUMBER='(3)';
      PINUSE='POWER';
      NO_LOAD_CHECK='Both';
      NO_IO_CHECK='Both';
      NO_ASSERT_CHECK='TRUE';
      NO_DIR_CHECK='TRUE';
      ALLOW_CONNECT='TRUE';
    'OE':
      PIN_NUMBER='(1)';
      INPUT_LOAD='(-0.01,0.01)';
      PINUSE='IN';
  end_pin;
  body
      PART_NAME='74LVC1G126SE7';
      BODY_NAME='74LVC1G126SE7';
      PHYS_DES_PREFIX='U';
      CLASS='IC';
      STANDARD='';
      LIFECYCLE='';
      JEDEC_TYPE='SOT353_0-65_2X1-25';
      DESCRIPTION='IC OTHER(5P) 74LVC1G126SE-7 (SOT353)';
      MANUFTR='DDS';
      MANUF_PN='74LVC1G126SE-7';
      RD_CMPLS_LVL='EP(V1)';
      CMPLS_LVL='EP(V1)';
      FROM_PJ='F0C-IVES';
      DIP_SMD='';
      DATA='DDS_74LVC1G126SE-7.pdf';
      EE_CHECK_LIST='';
      FP_ECN='';
      PSL='';
      CREATOR='';
      STATUS='';
      MSD='';
      ESD_CDM='';
      ESD_HBM='';
      ESD_MM='';
      PIN_LENGTH_SHORT_PIN='0 MILS';
      PIN_LENGTH_LONG_PIN='0 MILS';
      CREATEDAY='20210615';
      PARENT_PART_TYPE='74LVC1G126SE7';
      PARENT_PPT='74LVC1G126SE7';
      PARENT_PPT_PART='74LVC1G126SE7-74LVC1G126SE-7,SMLF,IC,AL1G0126009';
  end_body;
end_primitive;
primitive '74LVC1G17GW-74LVC1G17GW,SMLF,IA';
  pin
    'VCC':
      PIN_NUMBER='(5)';
      PINUSE='POWER';
      NO_LOAD_CHECK='Both';
      NO_IO_CHECK='Both';
      NO_ASSERT_CHECK='TRUE';
      NO_DIR_CHECK='TRUE';
      ALLOW_CONNECT='TRUE';
    'A':
      PIN_NUMBER='(2)';
      INPUT_LOAD='(-0.01,0.01)';
      PINUSE='IN';
    'GND':
      PIN_NUMBER='(3)';
      PINUSE='POWER';
      NO_LOAD_CHECK='Both';
      NO_IO_CHECK='Both';
      NO_ASSERT_CHECK='TRUE';
      NO_DIR_CHECK='TRUE';
      ALLOW_CONNECT='TRUE';
    'Y':
      PIN_NUMBER='(4)';
      OUTPUT_TYPE='(OC,AND)';
      OUTPUT_LOAD='(1.0,*)';
      PINUSE='OCA';
    'NC':
      PIN_NUMBER='(1)';
      OUTPUT_TYPE='(TS,TS)';
      INPUT_LOAD='(-0.01,0.01)';
      OUTPUT_LOAD='(1.0,-1.0)';
      PINUSE='TRI';
  end_pin;
  body
      PART_NAME='74LVC1G17GW';
      BODY_NAME='74LVC1G17GW';
      PHYS_DES_PREFIX='U';
      CLASS='IC';
      STANDARD='';
      LIFECYCLE='';
      JEDEC_TYPE='TSSOP5';
      DESCRIPTION='IC OTHER(5P) 74LVC1G17GW(TSSOP)';
      MANUFTR='NXP';
      MANUF_PN='74LVC1G17GW';
      RD_CMPLS_LVL='EP(V1)';
      CMPLS_LVL='EP(V1)';
      FROM_PJ='MF1-EUPHIE';
      DIP_SMD='';
      DATA='NXP_74LVC1G17.pdf';
      EE_CHECK_LIST='';
      FP_ECN='';
      PSL='';
      CREATOR='';
      STATUS='';
      CREATEDAY='20140828';
      PARENT_PART_TYPE='74LVC1G17GW';
      PARENT_PPT='74LVC1G17GW';
      PARENT_PPT_PART='74LVC1G17GW-74LVC1G17GW,SMLF,IC,AL1G0017K01';
  end_body;
end_primitive;
primitive '74LVC1G66GV-74LVC1G66GV,SMLF,IA';
  pin
    'Y':
      PIN_NUMBER='(1)';
      BIDIRECTIONAL='TRUE';
      INPUT_LOAD='(-0.01,0.01)';
      OUTPUT_LOAD='(1.0,-1.0)';
      PINUSE='BI';
    'Z':
      PIN_NUMBER='(2)';
      BIDIRECTIONAL='TRUE';
      INPUT_LOAD='(-0.01,0.01)';
      OUTPUT_LOAD='(1.0,-1.0)';
      PINUSE='BI';
    'GND':
      PIN_NUMBER='(3)';
      PINUSE='POWER';
      NO_LOAD_CHECK='Both';
      NO_IO_CHECK='Both';
      NO_ASSERT_CHECK='TRUE';
      NO_DIR_CHECK='TRUE';
      ALLOW_CONNECT='TRUE';
    'E':
      PIN_NUMBER='(4)';
      INPUT_LOAD='(-0.01,0.01)';
      PINUSE='IN';
    'VCC':
      PIN_NUMBER='(5)';
      PINUSE='POWER';
      NO_LOAD_CHECK='Both';
      NO_IO_CHECK='Both';
      NO_ASSERT_CHECK='TRUE';
      NO_DIR_CHECK='TRUE';
      ALLOW_CONNECT='TRUE';
  end_pin;
  body
      PART_NAME='74LVC1G66GV';
      BODY_NAME='74LVC1G66GV';
      PHYS_DES_PREFIX='U';
      CLASS='IC';
      STANDARD='';
      LIFECYCLE='';
      JEDEC_TYPE='SC74AXA';
      DESCRIPTION='IC(5P) 74LVC1G66GV(SOT753)';
      MANUFTR='PHI';
      MANUF_PN='74LVC1G66GV';
      RD_CMPLS_LVL='';
      CMPLS_LVL='EP';
      FROM_PJ='S4P-FRANK';
      DIP_SMD='';
      DATA='PHI_74LVC1G66.pdf';
      EE_CHECK_LIST='SC74AXA.xls';
      FP_ECN='';
      PSL='';
      CREATOR='';
      STATUS='';
      CREATEDAY='20140912';
      PARENT_PART_TYPE='74LVC1G66GV';
      PARENT_PPT='74LVC1G66GV';
      PARENT_PPT_PART='74LVC1G66GV-74LVC1G66GV,SMLF,IC,AL001G66000';
  end_body;
end_primitive;
primitive '74LVC1G74DP-74LVC1G74DP,SMLF,IA';
  pin
    'CP':
      PIN_NUMBER='(1)';
      INPUT_LOAD='(-0.01,0.01)';
      PINUSE='IN';
    'D':
      PIN_NUMBER='(2)';
      INPUT_LOAD='(-0.01,0.01)';
      PINUSE='IN';
    'Q_N':
      PIN_NUMBER='(3)';
      OUTPUT_LOAD='(1.0,-1.0)';
      PINUSE='OUT';
    'GND':
      PIN_NUMBER='(4)';
      PINUSE='POWER';
      NO_LOAD_CHECK='Both';
      NO_IO_CHECK='Both';
      NO_ASSERT_CHECK='TRUE';
      NO_DIR_CHECK='TRUE';
      ALLOW_CONNECT='TRUE';
    'VCC':
      PIN_NUMBER='(8)';
      PINUSE='POWER';
      NO_LOAD_CHECK='Both';
      NO_IO_CHECK='Both';
      NO_ASSERT_CHECK='TRUE';
      NO_DIR_CHECK='TRUE';
      ALLOW_CONNECT='TRUE';
    'RD_N':
      PIN_NUMBER='(6)';
      INPUT_LOAD='(-0.01,0.01)';
      PINUSE='IN';
    'SD_N':
      PIN_NUMBER='(7)';
      INPUT_LOAD='(-0.01,0.01)';
      PINUSE='IN';
    'Q':
      PIN_NUMBER='(5)';
      OUTPUT_LOAD='(1.0,-1.0)';
      PINUSE='OUT';
  end_pin;
  body
      PART_NAME='74LVC1G74DP';
      BODY_NAME='74LVC1G74DP';
      PHYS_DES_PREFIX='U';
      CLASS='IC';
      STANDARD='';
      LIFECYCLE='';
      JEDEC_TYPE='TSSOP8_0-65_3X3';
      DESCRIPTION='IC OTHER(8P) 74LVC1G74DP (TSSOP8)';
      MANUFTR='NXP';
      MANUF_PN='74LVC1G74DP';
      RD_CMPLS_LVL='EP(V1)';
      CMPLS_LVL='EP(V1)';
      FROM_PJ='A7K-DENNY';
      DIP_SMD='';
      DATA='NXP_74LVC1G74DP.pdf';
      EE_CHECK_LIST='';
      FP_ECN='';
      PSL='';
      CREATOR='';
      STATUS='';
      MSD='';
      ESD_CDM='';
      ESD_HBM='';
      ESD_MM='';
      PIN_LENGTH_SHORT_PIN='';
      PIN_LENGTH_LONG_PIN='';
      CREATEDAY='20161115';
      PARENT_PART_TYPE='74LVC1G74DP';
      PARENT_PPT='74LVC1G74DP';
      PARENT_PPT_PART='74LVC1G74DP-74LVC1G74DP,SMLF,IC,AL1G0074K01';
  end_body;
end_primitive;
primitive '74LVC2G07DW7-74LVC2G07DW-7,SMLA';
  pin
    '1A':
      PIN_NUMBER='(1)';
      INPUT_LOAD='(-0.01,0.01)';
      PINUSE='IN';
    '2A':
      PIN_NUMBER='(3)';
      INPUT_LOAD='(-0.01,0.01)';
      PINUSE='IN';
    '1Y':
      PIN_NUMBER='(6)';
      OUTPUT_LOAD='(1.0,-1.0)';
      PINUSE='OUT';
    '2Y':
      PIN_NUMBER='(4)';
      OUTPUT_LOAD='(1.0,-1.0)';
      PINUSE='OUT';
    'GND':
      PIN_NUMBER='(2)';
      PINUSE='POWER';
      NO_LOAD_CHECK='Both';
      NO_IO_CHECK='Both';
      NO_ASSERT_CHECK='TRUE';
      NO_DIR_CHECK='TRUE';
      ALLOW_CONNECT='TRUE';
    'VCC':
      PIN_NUMBER='(5)';
      PINUSE='POWER';
      NO_LOAD_CHECK='Both';
      NO_IO_CHECK='Both';
      NO_ASSERT_CHECK='TRUE';
      NO_DIR_CHECK='TRUE';
      ALLOW_CONNECT='TRUE';
  end_pin;
  body
      PART_NAME='74LVC2G07DW7';
      BODY_NAME='74LVC2G07DW7';
      PHYS_DES_PREFIX='U';
      CLASS='IC';
      STANDARD='';
      LIFECYCLE='';
      JEDEC_TYPE='SOT363_0-65_2X1-25XC';
      DESCRIPTION='IC OTHER(6P)74LVC2G07DW-7(SOT-363)';
      MANUFTR='DDS';
      MANUF_PN='74LVC2G07DW-7';
      RD_CMPLS_LVL='EP(V1)';
      CMPLS_LVL='EP(V1)';
      FROM_PJ='F0C-IVES';
      DIP_SMD='';
      DATA='DDS_74LVC2G07DW-7.pdf';
      EE_CHECK_LIST='';
      FP_ECN='';
      PSL='';
      CREATOR='';
      STATUS='';
      MSD='';
      ESD_CDM='';
      ESD_HBM='';
      ESD_MM='';
      PIN_LENGTH_SHORT_PIN='0 MILS';
      PIN_LENGTH_LONG_PIN='0 MILS';
      CREATEDAY='20210611';
      PARENT_PART_TYPE='74LVC2G07DW7';
      PARENT_PPT='74LVC2G07DW7';
      PARENT_PPT_PART='74LVC2G07DW7-74LVC2G07DW-7,SMLF,IC,AL002G07003';
  end_body;
end_primitive;
primitive 'AP2205W57-AP2205-W5-7,SMLF,IC,A';
  pin
    'VOUT':
      PIN_NUMBER='(5)';
      PINUSE='POWER';
      NO_LOAD_CHECK='Both';
      NO_IO_CHECK='Both';
      NO_ASSERT_CHECK='TRUE';
      NO_DIR_CHECK='TRUE';
      ALLOW_CONNECT='TRUE';
    'ADJ||NC':
      PIN_NUMBER='(4)';
      BIDIRECTIONAL='TRUE';
      INPUT_LOAD='(-0.01,0.01)';
      OUTPUT_LOAD='(1.0,-1.0)';
      PINUSE='BI';
    'VIN':
      PIN_NUMBER='(1)';
      PINUSE='POWER';
      NO_LOAD_CHECK='Both';
      NO_IO_CHECK='Both';
      NO_ASSERT_CHECK='TRUE';
      NO_DIR_CHECK='TRUE';
      ALLOW_CONNECT='TRUE';
    'GND':
      PIN_NUMBER='(2)';
      PINUSE='POWER';
      NO_LOAD_CHECK='Both';
      NO_IO_CHECK='Both';
      NO_ASSERT_CHECK='TRUE';
      NO_DIR_CHECK='TRUE';
      ALLOW_CONNECT='TRUE';
    'EN':
      PIN_NUMBER='(3)';
      INPUT_LOAD='(-0.01,0.01)';
      PINUSE='IN';
  end_pin;
  body
      PART_NAME='AP2205W57';
      BODY_NAME='AP2205W57';
      PHYS_DES_PREFIX='U';
      CLASS='IC';
      STANDARD='';
      LIFECYCLE='';
      JEDEC_TYPE='SOT25-5_0-95_2-96X1-6';
      DESCRIPTION='IC OTHER(5P)AP2205-W5-7(SOT25)';
      MANUFTR='DDS';
      MANUF_PN='AP2205-W5-7';
      RD_CMPLS_LVL='EP(V1)';
      CMPLS_LVL='';
      FROM_PJ='IXH-WISELY';
      DIP_SMD='';
      DATA='DDS_AP2205-W5-7.pdf';
      EE_CHECK_LIST='';
      FP_ECN='';
      PSL='';
      CREATOR='';
      STATUS='';
      MSD='Level-1';
      ESD_CDM='1000';
      ESD_HBM='2000';
      ESD_MM='NA';
      PIN_LENGTH_SHORT_PIN='0 MILS';
      PIN_LENGTH_LONG_PIN='0 MILS';
      CREATEDAY='20200206';
      PARENT_PART_TYPE='AP2205W57';
      PARENT_PPT='AP2205W57';
      PARENT_PPT_PART='AP2205W57-AP2205-W5-7,SMLF,IC,AL002205001';
  end_body;
end_primitive;
primitive 'AP22811AW57-AP22811AW5-7,SMLF,A';
  pin
    'OUT':
      PIN_NUMBER='(1)';
      OUTPUT_LOAD='(1.0,-1.0)';
      PINUSE='OUT';
    'GND':
      PIN_NUMBER='(2)';
      PINUSE='POWER';
      NO_LOAD_CHECK='Both';
      NO_IO_CHECK='Both';
      NO_ASSERT_CHECK='TRUE';
      NO_DIR_CHECK='TRUE';
      ALLOW_CONNECT='TRUE';
    'EN':
      PIN_NUMBER='(4)';
      INPUT_LOAD='(-0.01,0.01)';
      PINUSE='IN';
    'FLG#':
      PIN_NUMBER='(3)';
      OUTPUT_TYPE='(OC,AND)';
      OUTPUT_LOAD='(1.0,*)';
      PINUSE='OCA';
    'IN':
      PIN_NUMBER='(5)';
      INPUT_LOAD='(-0.01,0.01)';
      PINUSE='IN';
  end_pin;
  body
      PART_NAME='AP22811AW57';
      BODY_NAME='AP22811AW57';
      PHYS_DES_PREFIX='U';
      CLASS='IC';
      STANDARD='';
      LIFECYCLE='';
      JEDEC_TYPE='SOT25-5_0-95_3X1-6';
      DESCRIPTION='IC OTHER(5P)AP22811AW5-7(SOT25)';
      MANUFTR='DDS';
      MANUF_PN='AP22811AW5-7';
      RD_CMPLS_LVL='EP(V1)';
      CMPLS_LVL='EP(V1)';
      FROM_PJ='JBP-JACK';
      DIP_SMD='';
      DATA='DDS_AP22811AW5-7.pdf';
      EE_CHECK_LIST='';
      FP_ECN='';
      PSL='';
      CREATOR='';
      STATUS='';
      MSD='NA';
      ESD_CDM='NA';
      ESD_HBM='2KV';
      ESD_MM='200V';
      PIN_LENGTH_SHORT_PIN='0 MILS';
      PIN_LENGTH_LONG_PIN='0 MILS';
      CREATEDAY='20190201';
      PARENT_PART_TYPE='AP22811AW57';
      PARENT_PPT='AP22811AW57';
      PARENT_PPT_PART='AP22811AW57-AP22811AW5-7,SMLF,IC,AL022811000';
  end_body;
end_primitive;
primitive 'AST2600A3GP-AST2600A3-GP,SMLF,A';
  pin
    'MVREF_T5':
      PIN_NUMBER='(T5,0,0,0,0,0)';
      PINUSE='POWER';
      NO_LOAD_CHECK='Both';
      NO_IO_CHECK='Both';
      NO_ASSERT_CHECK='TRUE';
      NO_DIR_CHECK='TRUE';
      ALLOW_CONNECT='TRUE';
    'MIOZ':
      PIN_NUMBER='(P5,0,0,0,0,0)';
      BIDIRECTIONAL='TRUE';
      INPUT_LOAD='(-0.01,0.01)';
      OUTPUT_LOAD='(1.0,-1.0)';
      PINUSE='BI';
    'MRESET#':
      PIN_NUMBER='(L3,0,0,0,0,0)';
      OUTPUT_LOAD='(1.0,-1.0)';
      PINUSE='OUT';
    'MALERT#':
      PIN_NUMBER='(N4,0,0,0,0,0)';
      BIDIRECTIONAL='TRUE';
      INPUT_LOAD='(-0.01,0.01)';
      OUTPUT_LOAD='(1.0,-1.0)';
      PINUSE='BI';
    'MDQ0':
      PIN_NUMBER='(T3,0,0,0,0,0)';
      BIDIRECTIONAL='TRUE';
      INPUT_LOAD='(-0.01,0.01)';
      OUTPUT_LOAD='(1.0,-1.0)';
      PINUSE='BI';
    'MDQ1':
      PIN_NUMBER='(R4,0,0,0,0,0)';
      BIDIRECTIONAL='TRUE';
      INPUT_LOAD='(-0.01,0.01)';
      OUTPUT_LOAD='(1.0,-1.0)';
      PINUSE='BI';
    'MDQ2':
      PIN_NUMBER='(U1,0,0,0,0,0)';
      BIDIRECTIONAL='TRUE';
      INPUT_LOAD='(-0.01,0.01)';
      OUTPUT_LOAD='(1.0,-1.0)';
      PINUSE='BI';
    'MDQ3':
      PIN_NUMBER='(R3,0,0,0,0,0)';
      BIDIRECTIONAL='TRUE';
      INPUT_LOAD='(-0.01,0.01)';
      OUTPUT_LOAD='(1.0,-1.0)';
      PINUSE='BI';
    'MDQ4':
      PIN_NUMBER='(R1,0,0,0,0,0)';
      BIDIRECTIONAL='TRUE';
      INPUT_LOAD='(-0.01,0.01)';
      OUTPUT_LOAD='(1.0,-1.0)';
      PINUSE='BI';
    'MDQ5':
      PIN_NUMBER='(P1,0,0,0,0,0)';
      BIDIRECTIONAL='TRUE';
      INPUT_LOAD='(-0.01,0.01)';
      OUTPUT_LOAD='(1.0,-1.0)';
      PINUSE='BI';
    'MDQ6':
      PIN_NUMBER='(P2,0,0,0,0,0)';
      BIDIRECTIONAL='TRUE';
      INPUT_LOAD='(-0.01,0.01)';
      OUTPUT_LOAD='(1.0,-1.0)';
      PINUSE='BI';
    'MDQ7':
      PIN_NUMBER='(P3,0,0,0,0,0)';
      BIDIRECTIONAL='TRUE';
      INPUT_LOAD='(-0.01,0.01)';
      OUTPUT_LOAD='(1.0,-1.0)';
      PINUSE='BI';
    'MDQ8':
      PIN_NUMBER='(W2,0,0,0,0,0)';
      BIDIRECTIONAL='TRUE';
      INPUT_LOAD='(-0.01,0.01)';
      OUTPUT_LOAD='(1.0,-1.0)';
      PINUSE='BI';
    'MDQ9':
      PIN_NUMBER='(V3,0,0,0,0,0)';
      BIDIRECTIONAL='TRUE';
      INPUT_LOAD='(-0.01,0.01)';
      OUTPUT_LOAD='(1.0,-1.0)';
      PINUSE='BI';
    'MDQ10':
      PIN_NUMBER='(W1,0,0,0,0,0)';
      BIDIRECTIONAL='TRUE';
      INPUT_LOAD='(-0.01,0.01)';
      OUTPUT_LOAD='(1.0,-1.0)';
      PINUSE='BI';
    'MDQ11':
      PIN_NUMBER='(W3,0,0,0,0,0)';
      BIDIRECTIONAL='TRUE';
      INPUT_LOAD='(-0.01,0.01)';
      OUTPUT_LOAD='(1.0,-1.0)';
      PINUSE='BI';
    'MDQ12':
      PIN_NUMBER='(W4,0,0,0,0,0)';
      BIDIRECTIONAL='TRUE';
      INPUT_LOAD='(-0.01,0.01)';
      OUTPUT_LOAD='(1.0,-1.0)';
      PINUSE='BI';
    'MDQ13':
      PIN_NUMBER='(U4,0,0,0,0,0)';
      BIDIRECTIONAL='TRUE';
      INPUT_LOAD='(-0.01,0.01)';
      OUTPUT_LOAD='(1.0,-1.0)';
      PINUSE='BI';
    'MDQ14':
      PIN_NUMBER='(V4,0,0,0,0,0)';
      BIDIRECTIONAL='TRUE';
      INPUT_LOAD='(-0.01,0.01)';
      OUTPUT_LOAD='(1.0,-1.0)';
      PINUSE='BI';
    'MDQ15':
      PIN_NUMBER='(U3,0,0,0,0,0)';
      BIDIRECTIONAL='TRUE';
      INPUT_LOAD='(-0.01,0.01)';
      OUTPUT_LOAD='(1.0,-1.0)';
      PINUSE='BI';
    'MDQS0':
      PIN_NUMBER='(T2,0,0,0,0,0)';
      BIDIRECTIONAL='TRUE';
      INPUT_LOAD='(-0.01,0.01)';
      OUTPUT_LOAD='(1.0,-1.0)';
      PINUSE='BI';
    'MDQS1':
      PIN_NUMBER='(V2,0,0,0,0,0)';
      BIDIRECTIONAL='TRUE';
      INPUT_LOAD='(-0.01,0.01)';
      OUTPUT_LOAD='(1.0,-1.0)';
      PINUSE='BI';
    'MDQS0#':
      PIN_NUMBER='(T1,0,0,0,0,0)';
      BIDIRECTIONAL='TRUE';
      INPUT_LOAD='(-0.01,0.01)';
      OUTPUT_LOAD='(1.0,-1.0)';
      PINUSE='BI';
    'MDQS1#':
      PIN_NUMBER='(V1,0,0,0,0,0)';
      BIDIRECTIONAL='TRUE';
      INPUT_LOAD='(-0.01,0.01)';
      OUTPUT_LOAD='(1.0,-1.0)';
      PINUSE='BI';
    'GPIOW4||LCLK||ESPICK':
      PIN_NUMBER='(AE7,0,0,0,0,0)';
      BIDIRECTIONAL='TRUE';
      INPUT_LOAD='(-0.01,0.01)';
      OUTPUT_LOAD='(1.0,-1.0)';
      PINUSE='BI';
    'GPIOW5||LFRAME#||ESPICS#':
      PIN_NUMBER='(AF7,0,0,0,0,0)';
      BIDIRECTIONAL='TRUE';
      INPUT_LOAD='(-0.01,0.01)';
      OUTPUT_LOAD='(1.0,-1.0)';
      PINUSE='BI';
    'GPIOW6||LSIRQ#||ESPIALT#':
      PIN_NUMBER='(AD7,0,0,0,0,0)';
      BIDIRECTIONAL='TRUE';
      INPUT_LOAD='(-0.01,0.01)';
      OUTPUT_LOAD='(1.0,-1.0)';
      PINUSE='BI';
    'GPIOW7||LPCRST#||ESPIRST#':
      PIN_NUMBER='(AD8,0,0,0,0,0)';
      BIDIRECTIONAL='TRUE';
      INPUT_LOAD='(-0.01,0.01)';
      OUTPUT_LOAD='(1.0,-1.0)';
      PINUSE='BI';
    'GPIOF0||SD1CLK||PWM8':
      PIN_NUMBER='(D22,0,0,0,0,0)';
      BIDIRECTIONAL='TRUE';
      INPUT_LOAD='(-0.01,0.01)';
      OUTPUT_LOAD='(1.0,-1.0)';
      PINUSE='BI';
    'GPIOF1||SD1CMD||PWM9':
      PIN_NUMBER='(E22,0,0,0,0,0)';
      BIDIRECTIONAL='TRUE';
      INPUT_LOAD='(-0.01,0.01)';
      OUTPUT_LOAD='(1.0,-1.0)';
      PINUSE='BI';
    'GPIOF2||SD1DAT0||PWM10':
      PIN_NUMBER='(D23,0,0,0,0,0)';
      BIDIRECTIONAL='TRUE';
      INPUT_LOAD='(-0.01,0.01)';
      OUTPUT_LOAD='(1.0,-1.0)';
      PINUSE='BI';
    'GPIOF3||SD1DAT1||PWM11':
      PIN_NUMBER='(C23,0,0,0,0,0)';
      BIDIRECTIONAL='TRUE';
      INPUT_LOAD='(-0.01,0.01)';
      OUTPUT_LOAD='(1.0,-1.0)';
      PINUSE='BI';
    'GPIOF4||SD1DAT2||PWM12':
      PIN_NUMBER='(C22,0,0,0,0,0)';
      BIDIRECTIONAL='TRUE';
      INPUT_LOAD='(-0.01,0.01)';
      OUTPUT_LOAD='(1.0,-1.0)';
      PINUSE='BI';
    'GPIOF5||SD1DAT3||PWM13':
      PIN_NUMBER='(A25,0,0,0,0,0)';
      BIDIRECTIONAL='TRUE';
      INPUT_LOAD='(-0.01,0.01)';
      OUTPUT_LOAD='(1.0,-1.0)';
      PINUSE='BI';
    'GPIOF6||SD1CD#||PWM14':
      PIN_NUMBER='(A24,0,0,0,0,0)';
      BIDIRECTIONAL='TRUE';
      INPUT_LOAD='(-0.01,0.01)';
      OUTPUT_LOAD='(1.0,-1.0)';
      PINUSE='BI';
    'GPIOF7||SD1WP#||PWM15':
      PIN_NUMBER='(A23,0,0,0,0,0)';
      BIDIRECTIONAL='TRUE';
      INPUT_LOAD='(-0.01,0.01)';
      OUTPUT_LOAD='(1.0,-1.0)';
      PINUSE='BI';
    'GPIOG0||TXD6||SD2CLK||SALT9':
      PIN_NUMBER='(E21,0,0,0,0,0)';
      BIDIRECTIONAL='TRUE';
      INPUT_LOAD='(-0.01,0.01)';
      OUTPUT_LOAD='(1.0,-1.0)';
      PINUSE='BI';
    'GPIOG1||RXD6||SD2CMD||SALT10':
      PIN_NUMBER='(B22,0,0,0,0,0)';
      BIDIRECTIONAL='TRUE';
      INPUT_LOAD='(-0.01,0.01)';
      OUTPUT_LOAD='(1.0,-1.0)';
      PINUSE='BI';
    'GPIOG2||TXD7||SD2DAT0||SALT11':
      PIN_NUMBER='(C21,0,0,0,0,0)';
      BIDIRECTIONAL='TRUE';
      INPUT_LOAD='(-0.01,0.01)';
      OUTPUT_LOAD='(1.0,-1.0)';
      PINUSE='BI';
    'GPIOG3||RXD7||SD2DAT1||SALT12':
      PIN_NUMBER='(A22,0,0,0,0,0)';
      BIDIRECTIONAL='TRUE';
      INPUT_LOAD='(-0.01,0.01)';
      OUTPUT_LOAD='(1.0,-1.0)';
      PINUSE='BI';
    'GPIOG4||TXD8||SD2DAT2||SALT13':
      PIN_NUMBER='(A21,0,0,0,0,0)';
      BIDIRECTIONAL='TRUE';
      INPUT_LOAD='(-0.01,0.01)';
      OUTPUT_LOAD='(1.0,-1.0)';
      PINUSE='BI';
    'GPIOG5||RXD8||SD2DAT3||SALT14':
      PIN_NUMBER='(E20,0,0,0,0,0)';
      BIDIRECTIONAL='TRUE';
      INPUT_LOAD='(-0.01,0.01)';
      OUTPUT_LOAD='(1.0,-1.0)';
      PINUSE='BI';
    'GPIOG6||TXD9||SD2CD#||SALT15':
      PIN_NUMBER='(D21,0,0,0,0,0)';
      BIDIRECTIONAL='TRUE';
      INPUT_LOAD='(-0.01,0.01)';
      OUTPUT_LOAD='(1.0,-1.0)';
      PINUSE='BI';
    'GPIOG7||RXD9||SD2WP#||SALT16':
      PIN_NUMBER='(B21,0,0,0,0,0)';
      BIDIRECTIONAL='TRUE';
      INPUT_LOAD='(-0.01,0.01)';
      OUTPUT_LOAD='(1.0,-1.0)';
      PINUSE='BI';
    'PETXP':
      PIN_NUMBER='(AE4,0,0,0,0,0)';
      OUTPUT_LOAD='(1.0,-1.0)';
      PINUSE='OUT';
    'PETXN':
      PIN_NUMBER='(AE5,0,0,0,0,0)';
      OUTPUT_LOAD='(1.0,-1.0)';
      PINUSE='OUT';
    'PERST#':
      PIN_NUMBER='(A7,0,0,0,0,0)';
      INPUT_LOAD='(-0.01,0.01)';
      PINUSE='IN';
    'PEREFCLKP':
      PIN_NUMBER='(AD5,0,0,0,0,0)';
      INPUT_LOAD='(-0.01,0.01)';
      PINUSE='IN';
    'PEREFCLKN':
      PIN_NUMBER='(AD6,0,0,0,0,0)';
      INPUT_LOAD='(-0.01,0.01)';
      PINUSE='IN';
    'PERXP':
      PIN_NUMBER='(AF5,0,0,0,0,0)';
      INPUT_LOAD='(-0.01,0.01)';
      PINUSE='IN';
    'PERXN':
      PIN_NUMBER='(AF6,0,0,0,0,0)';
      INPUT_LOAD='(-0.01,0.01)';
      PINUSE='IN';
    'MVREF_U5':
      PIN_NUMBER='(U5,0,0,0,0,0)';
      PINUSE='POWER';
      NO_LOAD_CHECK='Both';
      NO_IO_CHECK='Both';
      NO_ASSERT_CHECK='TRUE';
      NO_DIR_CHECK='TRUE';
      ALLOW_CONNECT='TRUE';
    'MCK#':
      PIN_NUMBER='(K1,0,0,0,0,0)';
      OUTPUT_LOAD='(1.0,-1.0)';
      PINUSE='OUT';
    'MBA1':
      PIN_NUMBER='(H5,0,0,0,0,0)';
      OUTPUT_LOAD='(1.0,-1.0)';
      PINUSE='OUT';
    'MA3':
      PIN_NUMBER='(H3,0,0,0,0,0)';
      OUTPUT_LOAD='(1.0,-1.0)';
      PINUSE='OUT';
    'MA14||MACT#':
      PIN_NUMBER='(H1,0,0,0,0,0)';
      OUTPUT_LOAD='(1.0,-1.0)';
      PINUSE='OUT';
    'MBA2||MBG0':
      PIN_NUMBER='(G3,0,0,0,0,0)';
      OUTPUT_LOAD='(1.0,-1.0)';
      PINUSE='OUT';
    'GPIOJ2||HVI3C4SCL||SCL2':
      PIN_NUMBER='(E19,0,0,0,0,0)';
      BIDIRECTIONAL='TRUE';
      INPUT_LOAD='(-0.01,0.01)';
      OUTPUT_LOAD='(1.0,-1.0)';
      PINUSE='BI';
    'MA0':
      PIN_NUMBER='(F3,0,0,0,0,0)';
      OUTPUT_LOAD='(1.0,-1.0)';
      PINUSE='OUT';
    'MA13':
      PIN_NUMBER='(K3,0,0,0,0,0)';
      OUTPUT_LOAD='(1.0,-1.0)';
      PINUSE='OUT';
    'GPIOK3||SDA6':
      PIN_NUMBER='(E13,0,0,0,0,0)';
      BIDIRECTIONAL='TRUE';
      INPUT_LOAD='(-0.01,0.01)';
      OUTPUT_LOAD='(1.0,-1.0)';
      PINUSE='BI';
    'MBA0':
      PIN_NUMBER='(G4,0,0,0,0,0)';
      OUTPUT_LOAD='(1.0,-1.0)';
      PINUSE='OUT';
    'MA11':
      PIN_NUMBER='(G1,0,0,0,0,0)';
      OUTPUT_LOAD='(1.0,-1.0)';
      PINUSE='OUT';
    'MDM0':
      PIN_NUMBER='(N3,0,0,0,0,0)';
      OUTPUT_LOAD='(1.0,-1.0)';
      PINUSE='OUT';
    'GPIOJ7||HVI3C6SDA||SDA4':
      PIN_NUMBER='(D19,0,0,0,0,0)';
      BIDIRECTIONAL='TRUE';
      INPUT_LOAD='(-0.01,0.01)';
      OUTPUT_LOAD='(1.0,-1.0)';
      PINUSE='BI';
    'MA6':
      PIN_NUMBER='(M5,0,0,0,0,0)';
      OUTPUT_LOAD='(1.0,-1.0)';
      PINUSE='OUT';
    'MA5':
      PIN_NUMBER='(L1,0,0,0,0,0)';
      OUTPUT_LOAD='(1.0,-1.0)';
      PINUSE='OUT';
    'MCS#':
      PIN_NUMBER='(H2,0,0,0,0,0)';
      OUTPUT_LOAD='(1.0,-1.0)';
      PINUSE='OUT';
    'MA8':
      PIN_NUMBER='(M1,0,0,0,0,0)';
      OUTPUT_LOAD='(1.0,-1.0)';
      PINUSE='OUT';
    'MA12':
      PIN_NUMBER='(L4,0,0,0,0,0)';
      OUTPUT_LOAD='(1.0,-1.0)';
      PINUSE='OUT';
    'MDM1':
      PIN_NUMBER='(R5,0,0,0,0,0)';
      OUTPUT_LOAD='(1.0,-1.0)';
      PINUSE='OUT';
    'GPIOK5||SDA7':
      PIN_NUMBER='(E11,0,0,0,0,0)';
      BIDIRECTIONAL='TRUE';
      INPUT_LOAD='(-0.01,0.01)';
      OUTPUT_LOAD='(1.0,-1.0)';
      PINUSE='BI';
    'MA15||MBG1':
      PIN_NUMBER='(M3,0,0,0,0,0)';
      OUTPUT_LOAD='(1.0,-1.0)';
      PINUSE='OUT';
    'GPIOJ0||HVI3C3SCL||SCL1':
      PIN_NUMBER='(B20,0,0,0,0,0)';
      BIDIRECTIONAL='TRUE';
      INPUT_LOAD='(-0.01,0.01)';
      OUTPUT_LOAD='(1.0,-1.0)';
      PINUSE='BI';
    'GPIOK6||SCL8':
      PIN_NUMBER='(F13,0,0,0,0,0)';
      BIDIRECTIONAL='TRUE';
      INPUT_LOAD='(-0.01,0.01)';
      OUTPUT_LOAD='(1.0,-1.0)';
      PINUSE='BI';
    'MA10':
      PIN_NUMBER='(F2,0,0,0,0,0)';
      OUTPUT_LOAD='(1.0,-1.0)';
      PINUSE='OUT';
    'MRAS#':
      PIN_NUMBER='(J5,0,0,0,0,0)';
      OUTPUT_LOAD='(1.0,-1.0)';
      PINUSE='OUT';
    'MA4':
      PIN_NUMBER='(J3,0,0,0,0,0)';
      OUTPUT_LOAD='(1.0,-1.0)';
      PINUSE='OUT';
    'GPIOK4||SCL7':
      PIN_NUMBER='(D11,0,0,0,0,0)';
      BIDIRECTIONAL='TRUE';
      INPUT_LOAD='(-0.01,0.01)';
      OUTPUT_LOAD='(1.0,-1.0)';
      PINUSE='BI';
    'MA9':
      PIN_NUMBER='(N1,0,0,0,0,0)';
      OUTPUT_LOAD='(1.0,-1.0)';
      PINUSE='OUT';
    'GPIOJ4||HVI3C5SCL||SCL3':
      PIN_NUMBER='(C19,0,0,0,0,0)';
      BIDIRECTIONAL='TRUE';
      INPUT_LOAD='(-0.01,0.01)';
      OUTPUT_LOAD='(1.0,-1.0)';
      PINUSE='BI';
    'MA1':
      PIN_NUMBER='(K5,0,0,0,0,0)';
      OUTPUT_LOAD='(1.0,-1.0)';
      PINUSE='OUT';
    'GPIOK2||SCL6':
      PIN_NUMBER='(D12,0,0,0,0,0)';
      BIDIRECTIONAL='TRUE';
      INPUT_LOAD='(-0.01,0.01)';
      OUTPUT_LOAD='(1.0,-1.0)';
      PINUSE='BI';
    'GPIOJ3||HVI3C4SDA||SDA2':
      PIN_NUMBER='(D20,0,0,0,0,0)';
      BIDIRECTIONAL='TRUE';
      INPUT_LOAD='(-0.01,0.01)';
      OUTPUT_LOAD='(1.0,-1.0)';
      PINUSE='BI';
    'MCAS#':
      PIN_NUMBER='(J4,0,0,0,0,0)';
      OUTPUT_LOAD='(1.0,-1.0)';
      PINUSE='OUT';
    'GPIOW0||LAD0||ESPID0':
      PIN_NUMBER='(AB7,0,0,0,0,0)';
      BIDIRECTIONAL='TRUE';
      INPUT_LOAD='(-0.01,0.01)';
      OUTPUT_LOAD='(1.0,-1.0)';
      PINUSE='BI';
    'MCK':
      PIN_NUMBER='(K2,0,0,0,0,0)';
      OUTPUT_LOAD='(1.0,-1.0)';
      PINUSE='OUT';
    'MA2':
      PIN_NUMBER='(F1,0,0,0,0,0)';
      OUTPUT_LOAD='(1.0,-1.0)';
      PINUSE='OUT';
    'MWE#':
      PIN_NUMBER='(G5,0,0,0,0,0)';
      OUTPUT_LOAD='(1.0,-1.0)';
      PINUSE='OUT';
    'GPIOJ6||HVI3C6SCL||SCL4':
      PIN_NUMBER='(C20,0,0,0,0,0)';
      BIDIRECTIONAL='TRUE';
      INPUT_LOAD='(-0.01,0.01)';
      OUTPUT_LOAD='(1.0,-1.0)';
      PINUSE='BI';
    'MA7':
      PIN_NUMBER='(M2,0,0,0,0,0)';
      OUTPUT_LOAD='(1.0,-1.0)';
      PINUSE='OUT';
    'GPIOK0||SCL5':
      PIN_NUMBER='(A11,0,0,0,0,0)';
      BIDIRECTIONAL='TRUE';
      INPUT_LOAD='(-0.01,0.01)';
      OUTPUT_LOAD='(1.0,-1.0)';
      PINUSE='BI';
    'MODT':
      PIN_NUMBER='(J1,0,0,0,0,0)';
      OUTPUT_LOAD='(1.0,-1.0)';
      PINUSE='OUT';
    'GPIOW3||LAD3||ESPID3':
      PIN_NUMBER='(AC7,0,0,0,0,0)';
      BIDIRECTIONAL='TRUE';
      INPUT_LOAD='(-0.01,0.01)';
      OUTPUT_LOAD='(1.0,-1.0)';
      PINUSE='BI';
    'GPIOJ1||HVI3C3SDA||SDA1':
      PIN_NUMBER='(A20,0,0,0,0,0)';
      BIDIRECTIONAL='TRUE';
      INPUT_LOAD='(-0.01,0.01)';
      OUTPUT_LOAD='(1.0,-1.0)';
      PINUSE='BI';
    'GPIOW2||LAD2||ESPID2':
      PIN_NUMBER='(AC8,0,0,0,0,0)';
      BIDIRECTIONAL='TRUE';
      INPUT_LOAD='(-0.01,0.01)';
      OUTPUT_LOAD='(1.0,-1.0)';
      PINUSE='BI';
    'GPIOJ5||HVI3C5SDA||SDA3':
      PIN_NUMBER='(A19,0,0,0,0,0)';
      BIDIRECTIONAL='TRUE';
      INPUT_LOAD='(-0.01,0.01)';
      OUTPUT_LOAD='(1.0,-1.0)';
      PINUSE='BI';
    'GPIOW1||LAD1||ESPID1':
      PIN_NUMBER='(AB8,0,0,0,0,0)';
      BIDIRECTIONAL='TRUE';
      INPUT_LOAD='(-0.01,0.01)';
      OUTPUT_LOAD='(1.0,-1.0)';
      PINUSE='BI';
    'MCKE':
      PIN_NUMBER='(L5,0,0,0,0,0)';
      OUTPUT_LOAD='(1.0,-1.0)';
      PINUSE='OUT';
    'GPIOK1||SDA5':
      PIN_NUMBER='(C11,0,0,0,0,0)';
      BIDIRECTIONAL='TRUE';
      INPUT_LOAD='(-0.01,0.01)';
      OUTPUT_LOAD='(1.0,-1.0)';
      PINUSE='BI';
    'GPIOK7||SDA8':
      PIN_NUMBER='(E12,0,0,0,0,0)';
      BIDIRECTIONAL='TRUE';
      INPUT_LOAD='(-0.01,0.01)';
      OUTPUT_LOAD='(1.0,-1.0)';
      PINUSE='BI';
    'RCREFCLKP':
      PIN_NUMBER='(AE1,0,0,0,0,0)';
      INPUT_LOAD='(-0.01,0.01)';
      PINUSE='IN';
    'RCREFCLKN':
      PIN_NUMBER='(AE2,0,0,0,0,0)';
      INPUT_LOAD='(-0.01,0.01)';
      PINUSE='IN';
    'RCRXP':
      PIN_NUMBER='(AD2,0,0,0,0,0)';
      INPUT_LOAD='(-0.01,0.01)';
      PINUSE='IN';
    'RCRXN':
      PIN_NUMBER='(AD3,0,0,0,0,0)';
      INPUT_LOAD='(-0.01,0.01)';
      PINUSE='IN';
    'RCTXP':
      PIN_NUMBER='(AF2,0,0,0,0,0)';
      OUTPUT_LOAD='(1.0,-1.0)';
      PINUSE='OUT';
    'RCTXN':
      PIN_NUMBER='(AF3,0,0,0,0,0)';
      OUTPUT_LOAD='(1.0,-1.0)';
      PINUSE='OUT';
    'DPTXP0':
      PIN_NUMBER='(AC1,0,0,0,0,0)';
      OUTPUT_LOAD='(1.0,-1.0)';
      PINUSE='OUT';
    'DPTXN0':
      PIN_NUMBER='(AB1,0,0,0,0,0)';
      OUTPUT_LOAD='(1.0,-1.0)';
      PINUSE='OUT';
    'DPAUXP':
      PIN_NUMBER='(AC3,0,0,0,0,0)';
      BIDIRECTIONAL='TRUE';
      INPUT_LOAD='(-0.01,0.01)';
      OUTPUT_LOAD='(1.0,-1.0)';
      PINUSE='BI';
    'DPAUXN':
      PIN_NUMBER='(AB3,0,0,0,0,0)';
      BIDIRECTIONAL='TRUE';
      INPUT_LOAD='(-0.01,0.01)';
      OUTPUT_LOAD='(1.0,-1.0)';
      PINUSE='BI';
    'DPHPD':
      PIN_NUMBER='(C7,0,0,0,0,0)';
      INPUT_LOAD='(-0.01,0.01)';
      PINUSE='IN';
    'DPTXP1':
      PIN_NUMBER='(AB2,0,0,0,0,0)';
      OUTPUT_LOAD='(1.0,-1.0)';
      PINUSE='OUT';
    'DPTXN1':
      PIN_NUMBER='(AA2,0,0,0,0,0)';
      OUTPUT_LOAD='(1.0,-1.0)';
      PINUSE='OUT';
    'GPIOL0||SCL9':
      PIN_NUMBER='(D15,0,0,0,0,0)';
      BIDIRECTIONAL='TRUE';
      INPUT_LOAD='(-0.01,0.01)';
      OUTPUT_LOAD='(1.0,-1.0)';
      PINUSE='BI';
    'GPIOL1||SDA9':
      PIN_NUMBER='(A14,0,0,0,0,0)';
      BIDIRECTIONAL='TRUE';
      INPUT_LOAD='(-0.01,0.01)';
      OUTPUT_LOAD='(1.0,-1.0)';
      PINUSE='BI';
    'GPIOL2||SCL10':
      PIN_NUMBER='(E15,0,0,0,0,0)';
      BIDIRECTIONAL='TRUE';
      INPUT_LOAD='(-0.01,0.01)';
      OUTPUT_LOAD='(1.0,-1.0)';
      PINUSE='BI';
    'GPIOL3||SDA10':
      PIN_NUMBER='(A13,0,0,0,0,0)';
      BIDIRECTIONAL='TRUE';
      INPUT_LOAD='(-0.01,0.01)';
      OUTPUT_LOAD='(1.0,-1.0)';
      PINUSE='BI';
    'GPIOA0||SCL11||MDC3':
      PIN_NUMBER='(M24,0,0,0,0,0)';
      BIDIRECTIONAL='TRUE';
      INPUT_LOAD='(-0.01,0.01)';
      OUTPUT_LOAD='(1.0,-1.0)';
      PINUSE='BI';
    'GPIOA1||SDA11||MDIO3':
      PIN_NUMBER='(M25,0,0,0,0,0)';
      BIDIRECTIONAL='TRUE';
      INPUT_LOAD='(-0.01,0.01)';
      OUTPUT_LOAD='(1.0,-1.0)';
      PINUSE='BI';
    'GPIOA2||SCL12||MDC4':
      PIN_NUMBER='(L26,0,0,0,0,0)';
      BIDIRECTIONAL='TRUE';
      INPUT_LOAD='(-0.01,0.01)';
      OUTPUT_LOAD='(1.0,-1.0)';
      PINUSE='BI';
    'GPIOA3||SDA12||MDIO4':
      PIN_NUMBER='(K24,0,0,0,0,0)';
      BIDIRECTIONAL='TRUE';
      INPUT_LOAD='(-0.01,0.01)';
      OUTPUT_LOAD='(1.0,-1.0)';
      PINUSE='BI';
    'GPIOA6||MAC3LINK||SCL14||SGPM2O||SGPS2I0':
      PIN_NUMBER='(L23,0,0,0,0,0)';
      BIDIRECTIONAL='TRUE';
      INPUT_LOAD='(-0.01,0.01)';
      OUTPUT_LOAD='(1.0,-1.0)';
      PINUSE='BI';
    'GPIOA7||MAC4LINK||SDA14||SGPM2I||SGPS2I1':
      PIN_NUMBER='(K25,0,0,0,0,0)';
      BIDIRECTIONAL='TRUE';
      INPUT_LOAD='(-0.01,0.01)';
      OUTPUT_LOAD='(1.0,-1.0)';
      PINUSE='BI';
    'GPIOA4||MAC1LINK||SCL13||SGPM2CK||SGPS2CK':
      PIN_NUMBER='(K26,0,0,0,0,0)';
      BIDIRECTIONAL='TRUE';
      INPUT_LOAD='(-0.01,0.01)';
      OUTPUT_LOAD='(1.0,-1.0)';
      PINUSE='BI';
    'GPIOA5||MAC2LINK||SDA13||SGPM2LD||SGPS2LD':
      PIN_NUMBER='(L24,0,0,0,0,0)';
      BIDIRECTIONAL='TRUE';
      INPUT_LOAD='(-0.01,0.01)';
      OUTPUT_LOAD='(1.0,-1.0)';
      PINUSE='BI';
    'GPIOH0||SGPM1CK':
      PIN_NUMBER='(A18,0,0,0,0,0)';
      BIDIRECTIONAL='TRUE';
      INPUT_LOAD='(-0.01,0.01)';
      OUTPUT_LOAD='(1.0,-1.0)';
      PINUSE='BI';
    'GPIOH1||SGPM1LD':
      PIN_NUMBER='(B18,0,0,0,0,0)';
      BIDIRECTIONAL='TRUE';
      INPUT_LOAD='(-0.01,0.01)';
      OUTPUT_LOAD='(1.0,-1.0)';
      PINUSE='BI';
    'GPIOH2||SGPM1O':
      PIN_NUMBER='(C18,0,0,0,0,0)';
      BIDIRECTIONAL='TRUE';
      INPUT_LOAD='(-0.01,0.01)';
      OUTPUT_LOAD='(1.0,-1.0)';
      PINUSE='BI';
    'GPIOH3||SGPM1I':
      PIN_NUMBER='(A17,0,0,0,0,0)';
      BIDIRECTIONAL='TRUE';
      INPUT_LOAD='(-0.01,0.01)';
      OUTPUT_LOAD='(1.0,-1.0)';
      PINUSE='BI';
    'GPIOH4||SGPS1CK||SCL15':
      PIN_NUMBER='(D18,0,0,0,0,0)';
      BIDIRECTIONAL='TRUE';
      INPUT_LOAD='(-0.01,0.01)';
      OUTPUT_LOAD='(1.0,-1.0)';
      PINUSE='BI';
    'GPIOH5||SGPS1LD||SDA15':
      PIN_NUMBER='(B17,0,0,0,0,0)';
      BIDIRECTIONAL='TRUE';
      INPUT_LOAD='(-0.01,0.01)';
      OUTPUT_LOAD='(1.0,-1.0)';
      PINUSE='BI';
    'GPIOH6||SGPS1I0||SCL16':
      PIN_NUMBER='(C17,0,0,0,0,0)';
      BIDIRECTIONAL='TRUE';
      INPUT_LOAD='(-0.01,0.01)';
      OUTPUT_LOAD='(1.0,-1.0)';
      PINUSE='BI';
    'GPIOH7||SGPS1I1||SDA16':
      PIN_NUMBER='(E18,0,0,0,0,0)';
      BIDIRECTIONAL='TRUE';
      INPUT_LOAD='(-0.01,0.01)';
      OUTPUT_LOAD='(1.0,-1.0)';
      PINUSE='BI';
    'GPIOS2||PEWAKE#':
      PIN_NUMBER='(T26,0,0,0,0,0)';
      BIDIRECTIONAL='TRUE';
      INPUT_LOAD='(-0.01,0.01)';
      OUTPUT_LOAD='(1.0,-1.0)';
      PINUSE='BI';
    'GPIOS3||OSCCLK':
      PIN_NUMBER='(R24,0,0,0,0,0)';
      BIDIRECTIONAL='TRUE';
      INPUT_LOAD='(-0.01,0.01)';
      OUTPUT_LOAD='(1.0,-1.0)';
      PINUSE='BI';
    'FWSPICS0#':
      PIN_NUMBER='(0,AB14,0,0,0,0)';
      OUTPUT_LOAD='(1.0,-1.0)';
      PINUSE='OUT';
    'GPIOM0||NCTS1':
      PIN_NUMBER='(0,D14,0,0,0,0)';
      BIDIRECTIONAL='TRUE';
      INPUT_LOAD='(-0.01,0.01)';
      OUTPUT_LOAD='(1.0,-1.0)';
      PINUSE='BI';
    'GPIOM1||NDCD1':
      PIN_NUMBER='(0,B13,0,0,0,0)';
      BIDIRECTIONAL='TRUE';
      INPUT_LOAD='(-0.01,0.01)';
      OUTPUT_LOAD='(1.0,-1.0)';
      PINUSE='BI';
    'GPIOM2||NDSR1':
      PIN_NUMBER='(0,A12,0,0,0,0)';
      BIDIRECTIONAL='TRUE';
      INPUT_LOAD='(-0.01,0.01)';
      OUTPUT_LOAD='(1.0,-1.0)';
      PINUSE='BI';
    'GPIOM3||NRI1':
      PIN_NUMBER='(0,E14,0,0,0,0)';
      BIDIRECTIONAL='TRUE';
      INPUT_LOAD='(-0.01,0.01)';
      OUTPUT_LOAD='(1.0,-1.0)';
      PINUSE='BI';
    'GPIOM4||NDTR1':
      PIN_NUMBER='(0,B12,0,0,0,0)';
      BIDIRECTIONAL='TRUE';
      INPUT_LOAD='(-0.01,0.01)';
      OUTPUT_LOAD='(1.0,-1.0)';
      PINUSE='BI';
    'GPIOM5||NRTS1':
      PIN_NUMBER='(0,C12,0,0,0,0)';
      BIDIRECTIONAL='TRUE';
      INPUT_LOAD='(-0.01,0.01)';
      OUTPUT_LOAD='(1.0,-1.0)';
      PINUSE='BI';
    'GPIOM6||TXD1':
      PIN_NUMBER='(0,C13,0,0,0,0)';
      BIDIRECTIONAL='TRUE';
      INPUT_LOAD='(-0.01,0.01)';
      OUTPUT_LOAD='(1.0,-1.0)';
      PINUSE='BI';
    'GPIOM7||RXD1':
      PIN_NUMBER='(0,D13,0,0,0,0)';
      BIDIRECTIONAL='TRUE';
      INPUT_LOAD='(-0.01,0.01)';
      OUTPUT_LOAD='(1.0,-1.0)';
      PINUSE='BI';
    'GPION0||NCTS2':
      PIN_NUMBER='(0,P25,0,0,0,0)';
      BIDIRECTIONAL='TRUE';
      INPUT_LOAD='(-0.01,0.01)';
      OUTPUT_LOAD='(1.0,-1.0)';
      PINUSE='BI';
    'GPION1||NDCD2':
      PIN_NUMBER='(0,N23,0,0,0,0)';
      BIDIRECTIONAL='TRUE';
      INPUT_LOAD='(-0.01,0.01)';
      OUTPUT_LOAD='(1.0,-1.0)';
      PINUSE='BI';
    'GPION2||NDSR2':
      PIN_NUMBER='(0,N25,0,0,0,0)';
      BIDIRECTIONAL='TRUE';
      INPUT_LOAD='(-0.01,0.01)';
      OUTPUT_LOAD='(1.0,-1.0)';
      PINUSE='BI';
    'GPION3||NRI2':
      PIN_NUMBER='(0,N24,0,0,0,0)';
      BIDIRECTIONAL='TRUE';
      INPUT_LOAD='(-0.01,0.01)';
      OUTPUT_LOAD='(1.0,-1.0)';
      PINUSE='BI';
    'GPION4||NDTR2':
      PIN_NUMBER='(0,P26,0,0,0,0)';
      BIDIRECTIONAL='TRUE';
      INPUT_LOAD='(-0.01,0.01)';
      OUTPUT_LOAD='(1.0,-1.0)';
      PINUSE='BI';
    'GPION5||NRTS2':
      PIN_NUMBER='(0,M23,0,0,0,0)';
      BIDIRECTIONAL='TRUE';
      INPUT_LOAD='(-0.01,0.01)';
      OUTPUT_LOAD='(1.0,-1.0)';
      PINUSE='BI';
    'GPION6||TXD2':
      PIN_NUMBER='(0,N26,0,0,0,0)';
      BIDIRECTIONAL='TRUE';
      INPUT_LOAD='(-0.01,0.01)';
      OUTPUT_LOAD='(1.0,-1.0)';
      PINUSE='BI';
    'GPION7||RXD2':
      PIN_NUMBER='(0,M26,0,0,0,0)';
      BIDIRECTIONAL='TRUE';
      INPUT_LOAD='(-0.01,0.01)';
      OUTPUT_LOAD='(1.0,-1.0)';
      PINUSE='BI';
    'GPIOL5||RXD3':
      PIN_NUMBER='(0,F15,0,0,0,0)';
      BIDIRECTIONAL='TRUE';
      INPUT_LOAD='(-0.01,0.01)';
      OUTPUT_LOAD='(1.0,-1.0)';
      PINUSE='BI';
    'GPIOL4||TXD3':
      PIN_NUMBER='(0,C15,0,0,0,0)';
      BIDIRECTIONAL='TRUE';
      INPUT_LOAD='(-0.01,0.01)';
      OUTPUT_LOAD='(1.0,-1.0)';
      PINUSE='BI';
    'FWSPICS1#':
      PIN_NUMBER='(0,AA13,0,0,0,0)';
      OUTPUT_LOAD='(1.0,-1.0)';
      PINUSE='OUT';
    'FWSPICS2#':
      PIN_NUMBER='(0,AC13,0,0,0,0)';
      OUTPUT_LOAD='(1.0,-1.0)';
      PINUSE='OUT';
    'GPIOV0||SIOS3#':
      PIN_NUMBER='(0,AB15,0,0,0,0)';
      BIDIRECTIONAL='TRUE';
      INPUT_LOAD='(-0.01,0.01)';
      OUTPUT_LOAD='(1.0,-1.0)';
      PINUSE='BI';
    'GPIOV1||SIOS5#':
      PIN_NUMBER='(0,AF14,0,0,0,0)';
      BIDIRECTIONAL='TRUE';
      INPUT_LOAD='(-0.01,0.01)';
      OUTPUT_LOAD='(1.0,-1.0)';
      PINUSE='BI';
    'GPIOV2||SIOPWREQ#':
      PIN_NUMBER='(0,AD14,0,0,0,0)';
      BIDIRECTIONAL='TRUE';
      INPUT_LOAD='(-0.01,0.01)';
      OUTPUT_LOAD='(1.0,-1.0)';
      PINUSE='BI';
    'GPIOV3||SIOONCTRL#':
      PIN_NUMBER='(0,AC15,0,0,0,0)';
      BIDIRECTIONAL='TRUE';
      INPUT_LOAD='(-0.01,0.01)';
      OUTPUT_LOAD='(1.0,-1.0)';
      PINUSE='BI';
    'GPIOV4||SIOPWRGD':
      PIN_NUMBER='(0,AE15,0,0,0,0)';
      BIDIRECTIONAL='TRUE';
      INPUT_LOAD='(-0.01,0.01)';
      OUTPUT_LOAD='(1.0,-1.0)';
      PINUSE='BI';
    'GPIOV5||LPCPD#':
      PIN_NUMBER='(0,AE14,0,0,0,0)';
      BIDIRECTIONAL='TRUE';
      INPUT_LOAD='(-0.01,0.01)';
      OUTPUT_LOAD='(1.0,-1.0)';
      PINUSE='BI';
    'GPIOV6||LPCPME#':
      PIN_NUMBER='(0,AD15,0,0,0,0)';
      BIDIRECTIONAL='TRUE';
      INPUT_LOAD='(-0.01,0.01)';
      OUTPUT_LOAD='(1.0,-1.0)';
      PINUSE='BI';
    'GPIOV7||LPCSMI#':
      PIN_NUMBER='(0,AF15,0,0,0,0)';
      BIDIRECTIONAL='TRUE';
      INPUT_LOAD='(-0.01,0.01)';
      OUTPUT_LOAD='(1.0,-1.0)';
      PINUSE='BI';
    'FWSPICK':
      PIN_NUMBER='(0,AF13,0,0,0,0)';
      OUTPUT_LOAD='(1.0,-1.0)';
      PINUSE='OUT';
    'FWSPIMOSI':
      PIN_NUMBER='(0,AC14,0,0,0,0)';
      BIDIRECTIONAL='TRUE';
      INPUT_LOAD='(-0.01,0.01)';
      OUTPUT_LOAD='(1.0,-1.0)';
      PINUSE='BI';
    'FWSPIMISO':
      PIN_NUMBER='(0,AB13,0,0,0,0)';
      BIDIRECTIONAL='TRUE';
      INPUT_LOAD='(-0.01,0.01)';
      OUTPUT_LOAD='(1.0,-1.0)';
      PINUSE='BI';
    'GPIOY5||FWSPIDQ3':
      PIN_NUMBER='(0,AF12,0,0,0,0)';
      BIDIRECTIONAL='TRUE';
      INPUT_LOAD='(-0.01,0.01)';
      OUTPUT_LOAD='(1.0,-1.0)';
      PINUSE='BI';
    'GPIOY4||FWSPIDQ2':
      PIN_NUMBER='(0,AE12,0,0,0,0)';
      BIDIRECTIONAL='TRUE';
      INPUT_LOAD='(-0.01,0.01)';
      OUTPUT_LOAD='(1.0,-1.0)';
      PINUSE='BI';
    'GPIOY6||FWSPIABR':
      PIN_NUMBER='(0,AC12,0,0,0,0)';
      BIDIRECTIONAL='TRUE';
      INPUT_LOAD='(-0.01,0.01)';
      OUTPUT_LOAD='(1.0,-1.0)';
      PINUSE='BI';
    'GPIOY7||FWSPIWP#':
      PIN_NUMBER='(0,AB12,0,0,0,0)';
      BIDIRECTIONAL='TRUE';
      INPUT_LOAD='(-0.01,0.01)';
      OUTPUT_LOAD='(1.0,-1.0)';
      PINUSE='BI';
    'GPIOZ3||SPI1CK':
      PIN_NUMBER='(0,AB11,0,0,0,0)';
      BIDIRECTIONAL='TRUE';
      INPUT_LOAD='(-0.01,0.01)';
      OUTPUT_LOAD='(1.0,-1.0)';
      PINUSE='BI';
    'GPIOZ4||SPI1MOSI':
      PIN_NUMBER='(0,AC11,0,0,0,0)';
      BIDIRECTIONAL='TRUE';
      INPUT_LOAD='(-0.01,0.01)';
      OUTPUT_LOAD='(1.0,-1.0)';
      PINUSE='BI';
    'GPIOZ5||SPI1MISO':
      PIN_NUMBER='(0,AA11,0,0,0,0)';
      BIDIRECTIONAL='TRUE';
      INPUT_LOAD='(-0.01,0.01)';
      OUTPUT_LOAD='(1.0,-1.0)';
      PINUSE='BI';
    'GPIOZ6||SPI1DQ2||TXD13':
      PIN_NUMBER='(0,AD11,0,0,0,0)';
      BIDIRECTIONAL='TRUE';
      INPUT_LOAD='(-0.01,0.01)';
      OUTPUT_LOAD='(1.0,-1.0)';
      PINUSE='BI';
    'GPIOZ7||SPI1DQ3||RXD13':
      PIN_NUMBER='(0,AF10,0,0,0,0)';
      BIDIRECTIONAL='TRUE';
      INPUT_LOAD='(-0.01,0.01)';
      OUTPUT_LOAD='(1.0,-1.0)';
      PINUSE='BI';
    'SPI1CS0#':
      PIN_NUMBER='(0,AD13,0,0,0,0)';
      OUTPUT_LOAD='(1.0,-1.0)';
      PINUSE='OUT';
    'GPIOZ0||SPI1CS1#':
      PIN_NUMBER='(0,AC10,0,0,0,0)';
      BIDIRECTIONAL='TRUE';
      INPUT_LOAD='(-0.01,0.01)';
      OUTPUT_LOAD='(1.0,-1.0)';
      PINUSE='BI';
    'GPIOZ1||SPI1ABR':
      PIN_NUMBER='(0,AD10,0,0,0,0)';
      BIDIRECTIONAL='TRUE';
      INPUT_LOAD='(-0.01,0.01)';
      OUTPUT_LOAD='(1.0,-1.0)';
      PINUSE='BI';
    'GPIOZ2||SPI1WP#':
      PIN_NUMBER='(0,AE10,0,0,0,0)';
      BIDIRECTIONAL='TRUE';
      INPUT_LOAD='(-0.01,0.01)';
      OUTPUT_LOAD='(1.0,-1.0)';
      PINUSE='BI';
    'GPIOX3||SPI2CK':
      PIN_NUMBER='(0,AF8,0,0,0,0)';
      BIDIRECTIONAL='TRUE';
      INPUT_LOAD='(-0.01,0.01)';
      OUTPUT_LOAD='(1.0,-1.0)';
      PINUSE='BI';
    'GPIOX4||SPI2MOSI':
      PIN_NUMBER='(0,AB9,0,0,0,0)';
      BIDIRECTIONAL='TRUE';
      INPUT_LOAD='(-0.01,0.01)';
      OUTPUT_LOAD='(1.0,-1.0)';
      PINUSE='BI';
    'GPIOX5||SPI2MISO':
      PIN_NUMBER='(0,AD9,0,0,0,0)';
      BIDIRECTIONAL='TRUE';
      INPUT_LOAD='(-0.01,0.01)';
      OUTPUT_LOAD='(1.0,-1.0)';
      PINUSE='BI';
    'GPIOX6||SPI2DQ2||TXD12':
      PIN_NUMBER='(0,AF9,0,0,0,0)';
      BIDIRECTIONAL='TRUE';
      INPUT_LOAD='(-0.01,0.01)';
      OUTPUT_LOAD='(1.0,-1.0)';
      PINUSE='BI';
    'GPIOX7||SPI2DQ3||RXD12':
      PIN_NUMBER='(0,AB10,0,0,0,0)';
      BIDIRECTIONAL='TRUE';
      INPUT_LOAD='(-0.01,0.01)';
      OUTPUT_LOAD='(1.0,-1.0)';
      PINUSE='BI';
    'GPIOX0||SPI2CS0#':
      PIN_NUMBER='(0,AE8,0,0,0,0)';
      BIDIRECTIONAL='TRUE';
      INPUT_LOAD='(-0.01,0.01)';
      OUTPUT_LOAD='(1.0,-1.0)';
      PINUSE='BI';
    'GPIOX1||SPI2CS1#':
      PIN_NUMBER='(0,AA9,0,0,0,0)';
      BIDIRECTIONAL='TRUE';
      INPUT_LOAD='(-0.01,0.01)';
      OUTPUT_LOAD='(1.0,-1.0)';
      PINUSE='BI';
    'GPIOX2||SPI2CS2#':
      PIN_NUMBER='(0,AC9,0,0,0,0)';
      BIDIRECTIONAL='TRUE';
      INPUT_LOAD='(-0.01,0.01)';
      OUTPUT_LOAD='(1.0,-1.0)';
      PINUSE='BI';
    'GPIOB0||SALT1':
      PIN_NUMBER='(0,J26,0,0,0,0)';
      BIDIRECTIONAL='TRUE';
      INPUT_LOAD='(-0.01,0.01)';
      OUTPUT_LOAD='(1.0,-1.0)';
      PINUSE='BI';
    'GPIOB1||SALT2':
      PIN_NUMBER='(0,K23,0,0,0,0)';
      BIDIRECTIONAL='TRUE';
      INPUT_LOAD='(-0.01,0.01)';
      OUTPUT_LOAD='(1.0,-1.0)';
      PINUSE='BI';
    'GPIOB2||SALT3':
      PIN_NUMBER='(0,H26,0,0,0,0)';
      BIDIRECTIONAL='TRUE';
      INPUT_LOAD='(-0.01,0.01)';
      OUTPUT_LOAD='(1.0,-1.0)';
      PINUSE='BI';
    'GPIOB3||SALT4':
      PIN_NUMBER='(0,J25,0,0,0,0)';
      BIDIRECTIONAL='TRUE';
      INPUT_LOAD='(-0.01,0.01)';
      OUTPUT_LOAD='(1.0,-1.0)';
      PINUSE='BI';
    'GPIOB4||MDC2':
      PIN_NUMBER='(0,J23,0,0,0,0)';
      BIDIRECTIONAL='TRUE';
      INPUT_LOAD='(-0.01,0.01)';
      OUTPUT_LOAD='(1.0,-1.0)';
      PINUSE='BI';
    'GPIOB5||MDIO2':
      PIN_NUMBER='(0,G26,0,0,0,0)';
      BIDIRECTIONAL='TRUE';
      INPUT_LOAD='(-0.01,0.01)';
      OUTPUT_LOAD='(1.0,-1.0)';
      PINUSE='BI';
    'GPIOB6||TXD4':
      PIN_NUMBER='(0,H25,0,0,0,0)';
      BIDIRECTIONAL='TRUE';
      INPUT_LOAD='(-0.01,0.01)';
      OUTPUT_LOAD='(1.0,-1.0)';
      PINUSE='BI';
    'GPIOB7||RXD4':
      PIN_NUMBER='(0,J24,0,0,0,0)';
      BIDIRECTIONAL='TRUE';
      INPUT_LOAD='(-0.01,0.01)';
      OUTPUT_LOAD='(1.0,-1.0)';
      PINUSE='BI';
    'GPIOY0||SALT5||WDTRST1#':
      PIN_NUMBER='(0,AF11,0,0,0,0)';
      BIDIRECTIONAL='TRUE';
      INPUT_LOAD='(-0.01,0.01)';
      OUTPUT_LOAD='(1.0,-1.0)';
      PINUSE='BI';
    'GPIOY1||SALT6||WDTRST2#':
      PIN_NUMBER='(0,AD12,0,0,0,0)';
      BIDIRECTIONAL='TRUE';
      INPUT_LOAD='(-0.01,0.01)';
      OUTPUT_LOAD='(1.0,-1.0)';
      PINUSE='BI';
    'GPIOY2||SALT7||WDTRST3#':
      PIN_NUMBER='(0,AE11,0,0,0,0)';
      BIDIRECTIONAL='TRUE';
      INPUT_LOAD='(-0.01,0.01)';
      OUTPUT_LOAD='(1.0,-1.0)';
      PINUSE='BI';
    'GPIOY3||SALT8||WDTRST4#':
      PIN_NUMBER='(0,AA12,0,0,0,0)';
      BIDIRECTIONAL='TRUE';
      INPUT_LOAD='(-0.01,0.01)';
      OUTPUT_LOAD='(1.0,-1.0)';
      PINUSE='BI';
    'TXD5':
      PIN_NUMBER='(0,C8,0,0,0,0)';
      OUTPUT_LOAD='(1.0,-1.0)';
      PINUSE='OUT';
    'RXD5':
      PIN_NUMBER='(0,D8,0,0,0,0)';
      INPUT_LOAD='(-0.01,0.01)';
      PINUSE='IN';
    'RGMII3RXCK||RMII3RCLKI||GPIOC6':
      PIN_NUMBER='(0,G23,0,0,0,0)';
      BIDIRECTIONAL='TRUE';
      INPUT_LOAD='(-0.01,0.01)';
      OUTPUT_LOAD='(1.0,-1.0)';
      PINUSE='BI';
    'RGMII3RXCTL||GPIOC7':
      PIN_NUMBER='(0,G24,0,0,0,0)';
      BIDIRECTIONAL='TRUE';
      INPUT_LOAD='(-0.01,0.01)';
      OUTPUT_LOAD='(1.0,-1.0)';
      PINUSE='BI';
    'RGMII3RXD0||RMII3RXD0||GPIOD0':
      PIN_NUMBER='(0,F23,0,0,0,0)';
      BIDIRECTIONAL='TRUE';
      INPUT_LOAD='(-0.01,0.01)';
      OUTPUT_LOAD='(1.0,-1.0)';
      PINUSE='BI';
    'RGMII3RXD1||RMII3RXD1||GPIOD1':
      PIN_NUMBER='(0,F26,0,0,0,0)';
      BIDIRECTIONAL='TRUE';
      INPUT_LOAD='(-0.01,0.01)';
      OUTPUT_LOAD='(1.0,-1.0)';
      PINUSE='BI';
    'RGMII3RXD2||RMII3CRSDV||GPIOD2':
      PIN_NUMBER='(0,F25,0,0,0,0)';
      BIDIRECTIONAL='TRUE';
      INPUT_LOAD='(-0.01,0.01)';
      OUTPUT_LOAD='(1.0,-1.0)';
      PINUSE='BI';
    'RGMII3RXD3||RMII3RXER||GPIOD3':
      PIN_NUMBER='(0,E26,0,0,0,0)';
      BIDIRECTIONAL='TRUE';
      INPUT_LOAD='(-0.01,0.01)';
      OUTPUT_LOAD='(1.0,-1.0)';
      PINUSE='BI';
    'RGMII4RXCK||RMII4RCLKI||NCTS4||GPIOE2':
      PIN_NUMBER='(0,C25,0,0,0,0)';
      BIDIRECTIONAL='TRUE';
      INPUT_LOAD='(-0.01,0.01)';
      OUTPUT_LOAD='(1.0,-1.0)';
      PINUSE='BI';
    'RGMII4RXCTL||NDCD4||GPIOE3':
      PIN_NUMBER='(0,C26,0,0,0,0)';
      BIDIRECTIONAL='TRUE';
      INPUT_LOAD='(-0.01,0.01)';
      OUTPUT_LOAD='(1.0,-1.0)';
      PINUSE='BI';
    'RGMII4RXD0||RMII4RXD0||NDSR4||GPIOE4':
      PIN_NUMBER='(0,C24,0,0,0,0)';
      BIDIRECTIONAL='TRUE';
      INPUT_LOAD='(-0.01,0.01)';
      OUTPUT_LOAD='(1.0,-1.0)';
      PINUSE='BI';
    'RGMII4RXD1||RMII4RXD1||NRI4||GPIOE5':
      PIN_NUMBER='(0,B26,0,0,0,0)';
      BIDIRECTIONAL='TRUE';
      INPUT_LOAD='(-0.01,0.01)';
      OUTPUT_LOAD='(1.0,-1.0)';
      PINUSE='BI';
    'RGMII4RXD2||RMII4CRSDV||NDTR4||GPIOE6':
      PIN_NUMBER='(0,B25,0,0,0,0)';
      BIDIRECTIONAL='TRUE';
      INPUT_LOAD='(-0.01,0.01)';
      OUTPUT_LOAD='(1.0,-1.0)';
      PINUSE='BI';
    'RGMII4RXD3||RMII4RXER||NRTS4||GPIOE7':
      PIN_NUMBER='(0,B24,0,0,0,0)';
      BIDIRECTIONAL='TRUE';
      INPUT_LOAD='(-0.01,0.01)';
      OUTPUT_LOAD='(1.0,-1.0)';
      PINUSE='BI';
    'RGMII4TXCK||RMII4RCLKO||NCTS3||GPIOD4':
      PIN_NUMBER='(0,F24,0,0,0,0)';
      BIDIRECTIONAL='TRUE';
      INPUT_LOAD='(-0.01,0.01)';
      OUTPUT_LOAD='(1.0,-1.0)';
      PINUSE='BI';
    'RGMII4TXCTL||RMII4TXEN||NDCD3||GPIOD5':
      PIN_NUMBER='(0,E23,0,0,0,0)';
      BIDIRECTIONAL='TRUE';
      INPUT_LOAD='(-0.01,0.01)';
      OUTPUT_LOAD='(1.0,-1.0)';
      PINUSE='BI';
    'RGMII4TXD0||RMII4TXD0||NDSR3||GPIOD6':
      PIN_NUMBER='(0,E24,0,0,0,0)';
      BIDIRECTIONAL='TRUE';
      INPUT_LOAD='(-0.01,0.01)';
      OUTPUT_LOAD='(1.0,-1.0)';
      PINUSE='BI';
    'RGMII4TXD1||RMII4TXD1||NRI3||GPIOD7':
      PIN_NUMBER='(0,E25,0,0,0,0)';
      BIDIRECTIONAL='TRUE';
      INPUT_LOAD='(-0.01,0.01)';
      OUTPUT_LOAD='(1.0,-1.0)';
      PINUSE='BI';
    'RGMII4TXD2||NDTR3||GPIOE0':
      PIN_NUMBER='(0,D26,0,0,0,0)';
      BIDIRECTIONAL='TRUE';
      INPUT_LOAD='(-0.01,0.01)';
      OUTPUT_LOAD='(1.0,-1.0)';
      PINUSE='BI';
    'RGMII4TXD3||NRTS3||GPIOE1':
      PIN_NUMBER='(0,D24,0,0,0,0)';
      BIDIRECTIONAL='TRUE';
      INPUT_LOAD='(-0.01,0.01)';
      OUTPUT_LOAD='(1.0,-1.0)';
      PINUSE='BI';
    'RGMII3TXCK||RMII3RCLKO||GPIOC0':
      PIN_NUMBER='(0,H24,0,0,0,0)';
      BIDIRECTIONAL='TRUE';
      INPUT_LOAD='(-0.01,0.01)';
      OUTPUT_LOAD='(1.0,-1.0)';
      PINUSE='BI';
    'RGMII3TXCTL||RMII3TXEN||GPIOC1':
      PIN_NUMBER='(0,J22,0,0,0,0)';
      BIDIRECTIONAL='TRUE';
      INPUT_LOAD='(-0.01,0.01)';
      OUTPUT_LOAD='(1.0,-1.0)';
      PINUSE='BI';
    'RGMII3TXD0||RMII3TXD0||GPIOC2':
      PIN_NUMBER='(0,H22,0,0,0,0)';
      BIDIRECTIONAL='TRUE';
      INPUT_LOAD='(-0.01,0.01)';
      OUTPUT_LOAD='(1.0,-1.0)';
      PINUSE='BI';
    'RGMII3TXD1||RMII3TXD1||GPIOC3':
      PIN_NUMBER='(0,H23,0,0,0,0)';
      BIDIRECTIONAL='TRUE';
      INPUT_LOAD='(-0.01,0.01)';
      OUTPUT_LOAD='(1.0,-1.0)';
      PINUSE='BI';
    'RGMII3TXD2||GPIOC4':
      PIN_NUMBER='(0,G22,0,0,0,0)';
      BIDIRECTIONAL='TRUE';
      INPUT_LOAD='(-0.01,0.01)';
      OUTPUT_LOAD='(1.0,-1.0)';
      PINUSE='BI';
    'RGMII3TXD3||GPIOC5':
      PIN_NUMBER='(0,F22,0,0,0,0)';
      BIDIRECTIONAL='TRUE';
      INPUT_LOAD='(-0.01,0.01)';
      OUTPUT_LOAD='(1.0,-1.0)';
      PINUSE='BI';
    'RGMIICK':
      PIN_NUMBER='(0,A10,0,0,0,0)';
      INPUT_LOAD='(-0.01,0.01)';
      PINUSE='IN';
    'GPIOS0||MDC1':
      PIN_NUMBER='(0,R23,0,0,0,0)';
      BIDIRECTIONAL='TRUE';
      INPUT_LOAD='(-0.01,0.01)';
      OUTPUT_LOAD='(1.0,-1.0)';
      PINUSE='BI';
    'GPIOS1||MDIO1':
      PIN_NUMBER='(0,T25,0,0,0,0)';
      BIDIRECTIONAL='TRUE';
      INPUT_LOAD='(-0.01,0.01)';
      OUTPUT_LOAD='(1.0,-1.0)';
      PINUSE='BI';
    'GPIOS5||RXD10':
      PIN_NUMBER='(0,P24,0,0,0,0)';
      BIDIRECTIONAL='TRUE';
      INPUT_LOAD='(-0.01,0.01)';
      OUTPUT_LOAD='(1.0,-1.0)';
      PINUSE='BI';
    'GPIOS6||TXD11':
      PIN_NUMBER='(0,P23,0,0,0,0)';
      BIDIRECTIONAL='TRUE';
      INPUT_LOAD='(-0.01,0.01)';
      OUTPUT_LOAD='(1.0,-1.0)';
      PINUSE='BI';
    'GPIOS7||RXD11':
      PIN_NUMBER='(0,T24,0,0,0,0)';
      BIDIRECTIONAL='TRUE';
      INPUT_LOAD='(-0.01,0.01)';
      OUTPUT_LOAD='(1.0,-1.0)';
      PINUSE='BI';
    'GPIOS4||TXD10':
      PIN_NUMBER='(0,R26,0,0,0,0)';
      BIDIRECTIONAL='TRUE';
      INPUT_LOAD='(-0.01,0.01)';
      OUTPUT_LOAD='(1.0,-1.0)';
      PINUSE='BI';
    'GPIOI6||SIOPBI#':
      PIN_NUMBER='(0,B16,0,0,0,0)';
      BIDIRECTIONAL='TRUE';
      INPUT_LOAD='(-0.01,0.01)';
      OUTPUT_LOAD='(1.0,-1.0)';
      PINUSE='BI';
    'GPIOI5||SIOPBO#':
      PIN_NUMBER='(0,E16,0,0,0,0)';
      BIDIRECTIONAL='TRUE';
      INPUT_LOAD='(-0.01,0.01)';
      OUTPUT_LOAD='(1.0,-1.0)';
      PINUSE='BI';
    'GPIOI7||SIOSCI#':
      PIN_NUMBER='(0,A15,0,0,0,0)';
      BIDIRECTIONAL='TRUE';
      INPUT_LOAD='(-0.01,0.01)';
      OUTPUT_LOAD='(1.0,-1.0)';
      PINUSE='BI';
    'RGMII1RXCK||RMII1RCLKI||GPIO18A6':
      PIN_NUMBER='(0,0,B3,0,0,0)';
      BIDIRECTIONAL='TRUE';
      INPUT_LOAD='(-0.01,0.01)';
      OUTPUT_LOAD='(1.0,-1.0)';
      PINUSE='BI';
    'RGMII1RXCTL||GPIO18A7':
      PIN_NUMBER='(0,0,A2,0,0,0)';
      BIDIRECTIONAL='TRUE';
      INPUT_LOAD='(-0.01,0.01)';
      OUTPUT_LOAD='(1.0,-1.0)';
      PINUSE='BI';
    'RGMII1RXD0||RMII1RXD0||GPIO18B0':
      PIN_NUMBER='(0,0,B2,0,0,0)';
      BIDIRECTIONAL='TRUE';
      INPUT_LOAD='(-0.01,0.01)';
      OUTPUT_LOAD='(1.0,-1.0)';
      PINUSE='BI';
    'RGMII1RXD1||RMII1RXD1||GPIO18B1':
      PIN_NUMBER='(0,0,B1,0,0,0)';
      BIDIRECTIONAL='TRUE';
      INPUT_LOAD='(-0.01,0.01)';
      OUTPUT_LOAD='(1.0,-1.0)';
      PINUSE='BI';
    'RGMII1RXD2||RMII1CRSDV||GPIO18B2':
      PIN_NUMBER='(0,0,C4,0,0,0)';
      BIDIRECTIONAL='TRUE';
      INPUT_LOAD='(-0.01,0.01)';
      OUTPUT_LOAD='(1.0,-1.0)';
      PINUSE='BI';
    'RGMII1RXD3||RMII1RXER||GPIO18B3':
      PIN_NUMBER='(0,0,E5,0,0,0)';
      BIDIRECTIONAL='TRUE';
      INPUT_LOAD='(-0.01,0.01)';
      OUTPUT_LOAD='(1.0,-1.0)';
      PINUSE='BI';
    'RGMII1TXCK||RMII1RCLKO||GPIO18A0':
      PIN_NUMBER='(0,0,C6,0,0,0)';
      BIDIRECTIONAL='TRUE';
      INPUT_LOAD='(-0.01,0.01)';
      OUTPUT_LOAD='(1.0,-1.0)';
      PINUSE='BI';
    'RGMII1TXCTL||RMII1TXEN||GPIO18A1':
      PIN_NUMBER='(0,0,D6,0,0,0)';
      BIDIRECTIONAL='TRUE';
      INPUT_LOAD='(-0.01,0.01)';
      OUTPUT_LOAD='(1.0,-1.0)';
      PINUSE='BI';
    'RGMII1TXD0||RMII1TXD0||GPIO18A2':
      PIN_NUMBER='(0,0,D5,0,0,0)';
      BIDIRECTIONAL='TRUE';
      INPUT_LOAD='(-0.01,0.01)';
      OUTPUT_LOAD='(1.0,-1.0)';
      PINUSE='BI';
    'RGMII1TXD1||RMII1TXD1||GPIO18A3':
      PIN_NUMBER='(0,0,A3,0,0,0)';
      BIDIRECTIONAL='TRUE';
      INPUT_LOAD='(-0.01,0.01)';
      OUTPUT_LOAD='(1.0,-1.0)';
      PINUSE='BI';
    'RGMII1TXD2||GPIO18A4':
      PIN_NUMBER='(0,0,C5,0,0,0)';
      BIDIRECTIONAL='TRUE';
      INPUT_LOAD='(-0.01,0.01)';
      OUTPUT_LOAD='(1.0,-1.0)';
      PINUSE='BI';
    'RGMII1TXD3||GPIO18A5':
      PIN_NUMBER='(0,0,E6,0,0,0)';
      BIDIRECTIONAL='TRUE';
      INPUT_LOAD='(-0.01,0.01)';
      OUTPUT_LOAD='(1.0,-1.0)';
      PINUSE='BI';
    'RGMII2RXCK||RMII2RCLKI||GPIO18C2':
      PIN_NUMBER='(0,0,D2,0,0,0)';
      BIDIRECTIONAL='TRUE';
      INPUT_LOAD='(-0.01,0.01)';
      OUTPUT_LOAD='(1.0,-1.0)';
      PINUSE='BI';
    'RGMII2RXCTL||GPIO18C3':
      PIN_NUMBER='(0,0,E3,0,0,0)';
      BIDIRECTIONAL='TRUE';
      INPUT_LOAD='(-0.01,0.01)';
      OUTPUT_LOAD='(1.0,-1.0)';
      PINUSE='BI';
    'RGMII2RXD0||RMII2RXD0||GPIO18C4':
      PIN_NUMBER='(0,0,D1,0,0,0)';
      BIDIRECTIONAL='TRUE';
      INPUT_LOAD='(-0.01,0.01)';
      OUTPUT_LOAD='(1.0,-1.0)';
      PINUSE='BI';
    'RGMII2RXD1||RMII2RXD1||GPIO18C5':
      PIN_NUMBER='(0,0,F4,0,0,0)';
      BIDIRECTIONAL='TRUE';
      INPUT_LOAD='(-0.01,0.01)';
      OUTPUT_LOAD='(1.0,-1.0)';
      PINUSE='BI';
    'RGMII2RXD2||RMII2CRSDV||GPIO18C6':
      PIN_NUMBER='(0,0,E2,0,0,0)';
      BIDIRECTIONAL='TRUE';
      INPUT_LOAD='(-0.01,0.01)';
      OUTPUT_LOAD='(1.0,-1.0)';
      PINUSE='BI';
    'RGMII2RXD3||RMII2RXER||GPIO18C7':
      PIN_NUMBER='(0,0,E1,0,0,0)';
      BIDIRECTIONAL='TRUE';
      INPUT_LOAD='(-0.01,0.01)';
      OUTPUT_LOAD='(1.0,-1.0)';
      PINUSE='BI';
    'RGMII2TXCK||RMII2RCLKO||GPIO18B4':
      PIN_NUMBER='(0,0,D4,0,0,0)';
      BIDIRECTIONAL='TRUE';
      INPUT_LOAD='(-0.01,0.01)';
      OUTPUT_LOAD='(1.0,-1.0)';
      PINUSE='BI';
    'RGMII2TXCTL||RMII2TXEN||GPIO18B5':
      PIN_NUMBER='(0,0,C2,0,0,0)';
      BIDIRECTIONAL='TRUE';
      INPUT_LOAD='(-0.01,0.01)';
      OUTPUT_LOAD='(1.0,-1.0)';
      PINUSE='BI';
    'RGMII2TXD0||RMII2TXD0||GPIO18B6':
      PIN_NUMBER='(0,0,C1,0,0,0)';
      BIDIRECTIONAL='TRUE';
      INPUT_LOAD='(-0.01,0.01)';
      OUTPUT_LOAD='(1.0,-1.0)';
      PINUSE='BI';
    'RGMII2TXD1||RMII2TXD1||GPIO18B7':
      PIN_NUMBER='(0,0,D3,0,0,0)';
      BIDIRECTIONAL='TRUE';
      INPUT_LOAD='(-0.01,0.01)';
      OUTPUT_LOAD='(1.0,-1.0)';
      PINUSE='BI';
    'RGMII2TXD2||GPIO18C0':
      PIN_NUMBER='(0,0,E4,0,0,0)';
      BIDIRECTIONAL='TRUE';
      INPUT_LOAD='(-0.01,0.01)';
      OUTPUT_LOAD='(1.0,-1.0)';
      PINUSE='BI';
    'RGMII2TXD3||GPIO18C1':
      PIN_NUMBER='(0,0,F5,0,0,0)';
      BIDIRECTIONAL='TRUE';
      INPUT_LOAD='(-0.01,0.01)';
      OUTPUT_LOAD='(1.0,-1.0)';
      PINUSE='BI';
    'GPIO18D0||EMMCCLK':
      PIN_NUMBER='(0,0,AB4,0,0,0)';
      BIDIRECTIONAL='TRUE';
      INPUT_LOAD='(-0.01,0.01)';
      OUTPUT_LOAD='(1.0,-1.0)';
      PINUSE='BI';
    'GPIO18D1||EMMCCMD':
      PIN_NUMBER='(0,0,AA4,0,0,0)';
      BIDIRECTIONAL='TRUE';
      INPUT_LOAD='(-0.01,0.01)';
      OUTPUT_LOAD='(1.0,-1.0)';
      PINUSE='BI';
    'GPIO18D2||EMMCDAT0':
      PIN_NUMBER='(0,0,AC4,0,0,0)';
      BIDIRECTIONAL='TRUE';
      INPUT_LOAD='(-0.01,0.01)';
      OUTPUT_LOAD='(1.0,-1.0)';
      PINUSE='BI';
    'GPIO18D3||EMMCDAT1':
      PIN_NUMBER='(0,0,AA5,0,0,0)';
      BIDIRECTIONAL='TRUE';
      INPUT_LOAD='(-0.01,0.01)';
      OUTPUT_LOAD='(1.0,-1.0)';
      PINUSE='BI';
    'GPIO18D4||EMMCDAT2':
      PIN_NUMBER='(0,0,Y5,0,0,0)';
      BIDIRECTIONAL='TRUE';
      INPUT_LOAD='(-0.01,0.01)';
      OUTPUT_LOAD='(1.0,-1.0)';
      PINUSE='BI';
    'GPIO18D5||EMMCDAT3':
      PIN_NUMBER='(0,0,AB5,0,0,0)';
      BIDIRECTIONAL='TRUE';
      INPUT_LOAD='(-0.01,0.01)';
      OUTPUT_LOAD='(1.0,-1.0)';
      PINUSE='BI';
    'GPIO18D6||EMMCCD#':
      PIN_NUMBER='(0,0,AC5,0,0,0)';
      BIDIRECTIONAL='TRUE';
      INPUT_LOAD='(-0.01,0.01)';
      OUTPUT_LOAD='(1.0,-1.0)';
      PINUSE='BI';
    'GPIO18D7||EMMCWP#':
      PIN_NUMBER='(0,0,AB6,0,0,0)';
      BIDIRECTIONAL='TRUE';
      INPUT_LOAD='(-0.01,0.01)';
      OUTPUT_LOAD='(1.0,-1.0)';
      PINUSE='BI';
    'GPIO18E0||EMMCDAT4||FWSPI18CS#||VBCS#':
      PIN_NUMBER='(0,0,Y1,0,0,0)';
      BIDIRECTIONAL='TRUE';
      INPUT_LOAD='(-0.01,0.01)';
      OUTPUT_LOAD='(1.0,-1.0)';
      PINUSE='BI';
    'GPIO18E1||EMMCDAT5||FWSPI18CK||VBCK':
      PIN_NUMBER='(0,0,Y2,0,0,0)';
      BIDIRECTIONAL='TRUE';
      INPUT_LOAD='(-0.01,0.01)';
      OUTPUT_LOAD='(1.0,-1.0)';
      PINUSE='BI';
    'GPIO18E2||EMMCDAT6||FWSPI18MOSI||VBMOSI':
      PIN_NUMBER='(0,0,Y3,0,0,0)';
      BIDIRECTIONAL='TRUE';
      INPUT_LOAD='(-0.01,0.01)';
      OUTPUT_LOAD='(1.0,-1.0)';
      PINUSE='BI';
    'GPIO18E3||EMMCDAT7||FWSPI18MISO||VBMISO':
      PIN_NUMBER='(0,0,Y4,0,0,0)';
      BIDIRECTIONAL='TRUE';
      INPUT_LOAD='(-0.01,0.01)';
      OUTPUT_LOAD='(1.0,-1.0)';
      PINUSE='BI';
    'I3C1SCL':
      PIN_NUMBER='(0,0,AF23,0,0,0)';
      BIDIRECTIONAL='TRUE';
      INPUT_LOAD='(-0.01,0.01)';
      OUTPUT_LOAD='(1.0,-1.0)';
      PINUSE='BI';
    'I3C1SDA':
      PIN_NUMBER='(0,0,AE24,0,0,0)';
      BIDIRECTIONAL='TRUE';
      INPUT_LOAD='(-0.01,0.01)';
      OUTPUT_LOAD='(1.0,-1.0)';
      PINUSE='BI';
    'I3C2SCL':
      PIN_NUMBER='(0,0,AF22,0,0,0)';
      BIDIRECTIONAL='TRUE';
      INPUT_LOAD='(-0.01,0.01)';
      OUTPUT_LOAD='(1.0,-1.0)';
      PINUSE='BI';
    'I3C2SDA':
      PIN_NUMBER='(0,0,AE22,0,0,0)';
      BIDIRECTIONAL='TRUE';
      INPUT_LOAD='(-0.01,0.01)';
      OUTPUT_LOAD='(1.0,-1.0)';
      PINUSE='BI';
    'I3C3SCL||FSI1CLK':
      PIN_NUMBER='(0,0,AF25,0,0,0)';
      BIDIRECTIONAL='TRUE';
      INPUT_LOAD='(-0.01,0.01)';
      OUTPUT_LOAD='(1.0,-1.0)';
      PINUSE='BI';
    'I3C3SDA||FSI1DATA':
      PIN_NUMBER='(0,0,AE26,0,0,0)';
      BIDIRECTIONAL='TRUE';
      INPUT_LOAD='(-0.01,0.01)';
      OUTPUT_LOAD='(1.0,-1.0)';
      PINUSE='BI';
    'I3C4SCL||FSI2CLK':
      PIN_NUMBER='(0,0,AE25,0,0,0)';
      BIDIRECTIONAL='TRUE';
      INPUT_LOAD='(-0.01,0.01)';
      OUTPUT_LOAD='(1.0,-1.0)';
      PINUSE='BI';
    'I3C4SDA||FSI2DATA':
      PIN_NUMBER='(0,0,AF24,0,0,0)';
      BIDIRECTIONAL='TRUE';
      INPUT_LOAD='(-0.01,0.01)';
      OUTPUT_LOAD='(1.0,-1.0)';
      PINUSE='BI';
    'DACB':
      PIN_NUMBER='(0,0,0,AD21,0,0)';
      OUTPUT_LOAD='(1.0,-1.0)';
      PINUSE='OUT';
    'DACG':
      PIN_NUMBER='(0,0,0,AE21,0,0)';
      OUTPUT_LOAD='(1.0,-1.0)';
      PINUSE='OUT';
    'DACR':
      PIN_NUMBER='(0,0,0,AF21,0,0)';
      OUTPUT_LOAD='(1.0,-1.0)';
      PINUSE='OUT';
    'USB2AV33':
      PIN_NUMBER='(0,0,0,J10,0,0)';
      PINUSE='POWER';
      NO_LOAD_CHECK='Both';
      NO_IO_CHECK='Both';
      NO_ASSERT_CHECK='TRUE';
      NO_DIR_CHECK='TRUE';
      ALLOW_CONNECT='TRUE';
    'USB2A_DN':
      PIN_NUMBER='(0,0,0,B4,0,0)';
      BIDIRECTIONAL='TRUE';
      INPUT_LOAD='(-0.01,0.01)';
      OUTPUT_LOAD='(1.0,-1.0)';
      PINUSE='BI';
    'USB2A_DP':
      PIN_NUMBER='(0,0,0,A4,0,0)';
      BIDIRECTIONAL='TRUE';
      INPUT_LOAD='(-0.01,0.01)';
      OUTPUT_LOAD='(1.0,-1.0)';
      PINUSE='BI';
    'USB2B_DN':
      PIN_NUMBER='(0,0,0,B6,0,0)';
      BIDIRECTIONAL='TRUE';
      INPUT_LOAD='(-0.01,0.01)';
      OUTPUT_LOAD='(1.0,-1.0)';
      PINUSE='BI';
    'USB2B_DP':
      PIN_NUMBER='(0,0,0,A6,0,0)';
      BIDIRECTIONAL='TRUE';
      INPUT_LOAD='(-0.01,0.01)';
      OUTPUT_LOAD='(1.0,-1.0)';
      PINUSE='BI';
    'ADC0||GPIT0':
      PIN_NUMBER='(0,0,0,AD20,0,0)';
      INPUT_LOAD='(-0.01,0.01)';
      PINUSE='IN';
    'ADC1||GPIT1':
      PIN_NUMBER='(0,0,0,AC18,0,0)';
      INPUT_LOAD='(-0.01,0.01)';
      PINUSE='IN';
    'ADC2||GPIT2':
      PIN_NUMBER='(0,0,0,AE19,0,0)';
      INPUT_LOAD='(-0.01,0.01)';
      PINUSE='IN';
    'ADC3||GPIT3':
      PIN_NUMBER='(0,0,0,AD19,0,0)';
      INPUT_LOAD='(-0.01,0.01)';
      PINUSE='IN';
    'ADC4||GPIT4':
      PIN_NUMBER='(0,0,0,AC19,0,0)';
      INPUT_LOAD='(-0.01,0.01)';
      PINUSE='IN';
    'ADC5||GPIT5':
      PIN_NUMBER='(0,0,0,AB19,0,0)';
      INPUT_LOAD='(-0.01,0.01)';
      PINUSE='IN';
    'ADC6||GPIT6':
      PIN_NUMBER='(0,0,0,AB18,0,0)';
      INPUT_LOAD='(-0.01,0.01)';
      PINUSE='IN';
    'ADC7||GPIT7':
      PIN_NUMBER='(0,0,0,AE18,0,0)';
      INPUT_LOAD='(-0.01,0.01)';
      PINUSE='IN';
    'ADC8||GPIU0||SALT9':
      PIN_NUMBER='(0,0,0,AB16,0,0)';
      INPUT_LOAD='(-0.01,0.01)';
      PINUSE='IN';
    'ADC9||GPIU1||SALT10':
      PIN_NUMBER='(0,0,0,AA17,0,0)';
      INPUT_LOAD='(-0.01,0.01)';
      PINUSE='IN';
    'ADC10||GPIU2||SALT11':
      PIN_NUMBER='(0,0,0,AB17,0,0)';
      INPUT_LOAD='(-0.01,0.01)';
      PINUSE='IN';
    'ADC11||GPIU3||SALT12':
      PIN_NUMBER='(0,0,0,AE16,0,0)';
      INPUT_LOAD='(-0.01,0.01)';
      PINUSE='IN';
    'ADC12||GPIU4||SALT13':
      PIN_NUMBER='(0,0,0,AC16,0,0)';
      INPUT_LOAD='(-0.01,0.01)';
      PINUSE='IN';
    'ADC13||GPIU5||SALT14':
      PIN_NUMBER='(0,0,0,AA16,0,0)';
      INPUT_LOAD='(-0.01,0.01)';
      PINUSE='IN';
    'ADC14||GPIU6||SALT15':
      PIN_NUMBER='(0,0,0,AD16,0,0)';
      INPUT_LOAD='(-0.01,0.01)';
      PINUSE='IN';
    'ADC15||GPIU7||SALT16':
      PIN_NUMBER='(0,0,0,AC17,0,0)';
      INPUT_LOAD='(-0.01,0.01)';
      PINUSE='IN';
    'ENTEST':
      PIN_NUMBER='(0,0,0,C10,0,0)';
      INPUT_LOAD='(-0.01,0.01)';
      PINUSE='IN';
    'SRST#':
      PIN_NUMBER='(0,0,0,E10,0,0)';
      INPUT_LOAD='(-0.01,0.01)';
      PINUSE='IN';
    'EXTRST#':
      PIN_NUMBER='(0,0,0,B10,0,0)';
      INPUT_LOAD='(-0.01,0.01)';
      PINUSE='IN';
    'CLKIN':
      PIN_NUMBER='(0,0,0,D10,0,0)';
      INPUT_LOAD='(-0.01,0.01)';
      PINUSE='IN';
    'RSTIND#':
      PIN_NUMBER='(0,0,0,B7,0,0)';
      OUTPUT_LOAD='(1.0,-1.0)';
      PINUSE='OUT';
    'NTRST||MNTRST1':
      PIN_NUMBER='(0,0,0,F11,0,0)';
      BIDIRECTIONAL='TRUE';
      INPUT_LOAD='(-0.01,0.01)';
      OUTPUT_LOAD='(1.0,-1.0)';
      PINUSE='BI';
    'TCK||MTCK1':
      PIN_NUMBER='(0,0,0,B9,0,0)';
      BIDIRECTIONAL='TRUE';
      INPUT_LOAD='(-0.01,0.01)';
      OUTPUT_LOAD='(1.0,-1.0)';
      PINUSE='BI';
    'TDI||MTDI1':
      PIN_NUMBER='(0,0,0,D9,0,0)';
      BIDIRECTIONAL='TRUE';
      INPUT_LOAD='(-0.01,0.01)';
      OUTPUT_LOAD='(1.0,-1.0)';
      PINUSE='BI';
    'TDO||MTDO1':
      PIN_NUMBER='(0,0,0,C9,0,0)';
      BIDIRECTIONAL='TRUE';
      INPUT_LOAD='(-0.01,0.01)';
      OUTPUT_LOAD='(1.0,-1.0)';
      PINUSE='BI';
    'TMS||MTMS1':
      PIN_NUMBER='(0,0,0,A9,0,0)';
      BIDIRECTIONAL='TRUE';
      INPUT_LOAD='(-0.01,0.01)';
      OUTPUT_LOAD='(1.0,-1.0)';
      PINUSE='BI';
    'GPIOL6||VGAHS':
      PIN_NUMBER='(0,0,0,B14,0,0)';
      BIDIRECTIONAL='TRUE';
      INPUT_LOAD='(-0.01,0.01)';
      OUTPUT_LOAD='(1.0,-1.0)';
      PINUSE='BI';
    'GPIOL7||VGAVS':
      PIN_NUMBER='(0,0,0,C14,0,0)';
      BIDIRECTIONAL='TRUE';
      INPUT_LOAD='(-0.01,0.01)';
      OUTPUT_LOAD='(1.0,-1.0)';
      PINUSE='BI';
    'DDCCLK':
      PIN_NUMBER='(0,0,0,B8,0,0)';
      OUTPUT_LOAD='(1.0,-1.0)';
      PINUSE='OUT';
    'DDCDAT':
      PIN_NUMBER='(0,0,0,A8,0,0)';
      OUTPUT_LOAD='(1.0,-1.0)';
      PINUSE='OUT';
    'GPIOO0||PWM0':
      PIN_NUMBER='(0,0,0,AD26,0,0)';
      BIDIRECTIONAL='TRUE';
      INPUT_LOAD='(-0.01,0.01)';
      OUTPUT_LOAD='(1.0,-1.0)';
      PINUSE='BI';
    'GPIOO1||PWM1':
      PIN_NUMBER='(0,0,0,AD22,0,0)';
      BIDIRECTIONAL='TRUE';
      INPUT_LOAD='(-0.01,0.01)';
      OUTPUT_LOAD='(1.0,-1.0)';
      PINUSE='BI';
    'GPIOO2||PWM2':
      PIN_NUMBER='(0,0,0,AD23,0,0)';
      BIDIRECTIONAL='TRUE';
      INPUT_LOAD='(-0.01,0.01)';
      OUTPUT_LOAD='(1.0,-1.0)';
      PINUSE='BI';
    'GPIOO3||PWM3':
      PIN_NUMBER='(0,0,0,AD24,0,0)';
      BIDIRECTIONAL='TRUE';
      INPUT_LOAD='(-0.01,0.01)';
      OUTPUT_LOAD='(1.0,-1.0)';
      PINUSE='BI';
    'GPIOO4||PWM4':
      PIN_NUMBER='(0,0,0,AD25,0,0)';
      BIDIRECTIONAL='TRUE';
      INPUT_LOAD='(-0.01,0.01)';
      OUTPUT_LOAD='(1.0,-1.0)';
      PINUSE='BI';
    'GPIOO5||PWM5':
      PIN_NUMBER='(0,0,0,AC22,0,0)';
      BIDIRECTIONAL='TRUE';
      INPUT_LOAD='(-0.01,0.01)';
      OUTPUT_LOAD='(1.0,-1.0)';
      PINUSE='BI';
    'GPIOO6||PWM6':
      PIN_NUMBER='(0,0,0,AC24,0,0)';
      BIDIRECTIONAL='TRUE';
      INPUT_LOAD='(-0.01,0.01)';
      OUTPUT_LOAD='(1.0,-1.0)';
      PINUSE='BI';
    'GPIOO7||PWM7':
      PIN_NUMBER='(0,0,0,AC23,0,0)';
      BIDIRECTIONAL='TRUE';
      INPUT_LOAD='(-0.01,0.01)';
      OUTPUT_LOAD='(1.0,-1.0)';
      PINUSE='BI';
    'GPIOQ0||TACH0':
      PIN_NUMBER='(0,0,0,AA25,0,0)';
      BIDIRECTIONAL='TRUE';
      INPUT_LOAD='(-0.01,0.01)';
      OUTPUT_LOAD='(1.0,-1.0)';
      PINUSE='BI';
    'GPIOQ1||TACH1':
      PIN_NUMBER='(0,0,0,AB25,0,0)';
      BIDIRECTIONAL='TRUE';
      INPUT_LOAD='(-0.01,0.01)';
      OUTPUT_LOAD='(1.0,-1.0)';
      PINUSE='BI';
    'GPIOQ2||TACH2':
      PIN_NUMBER='(0,0,0,Y24,0,0)';
      BIDIRECTIONAL='TRUE';
      INPUT_LOAD='(-0.01,0.01)';
      OUTPUT_LOAD='(1.0,-1.0)';
      PINUSE='BI';
    'GPIOQ3||TACH3':
      PIN_NUMBER='(0,0,0,AB26,0,0)';
      BIDIRECTIONAL='TRUE';
      INPUT_LOAD='(-0.01,0.01)';
      OUTPUT_LOAD='(1.0,-1.0)';
      PINUSE='BI';
    'GPIOQ4||TACH4':
      PIN_NUMBER='(0,0,0,Y26,0,0)';
      BIDIRECTIONAL='TRUE';
      INPUT_LOAD='(-0.01,0.01)';
      OUTPUT_LOAD='(1.0,-1.0)';
      PINUSE='BI';
    'GPIOQ5||TACH5':
      PIN_NUMBER='(0,0,0,AC26,0,0)';
      BIDIRECTIONAL='TRUE';
      INPUT_LOAD='(-0.01,0.01)';
      OUTPUT_LOAD='(1.0,-1.0)';
      PINUSE='BI';
    'GPIOQ6||TACH6':
      PIN_NUMBER='(0,0,0,Y25,0,0)';
      BIDIRECTIONAL='TRUE';
      INPUT_LOAD='(-0.01,0.01)';
      OUTPUT_LOAD='(1.0,-1.0)';
      PINUSE='BI';
    'GPIOQ7||TACH7':
      PIN_NUMBER='(0,0,0,AA26,0,0)';
      BIDIRECTIONAL='TRUE';
      INPUT_LOAD='(-0.01,0.01)';
      OUTPUT_LOAD='(1.0,-1.0)';
      PINUSE='BI';
    'GPIOR0||TACH8':
      PIN_NUMBER='(0,0,0,V25,0,0)';
      BIDIRECTIONAL='TRUE';
      INPUT_LOAD='(-0.01,0.01)';
      OUTPUT_LOAD='(1.0,-1.0)';
      PINUSE='BI';
    'GPIOR1||TACH9':
      PIN_NUMBER='(0,0,0,U24,0,0)';
      BIDIRECTIONAL='TRUE';
      INPUT_LOAD='(-0.01,0.01)';
      OUTPUT_LOAD='(1.0,-1.0)';
      PINUSE='BI';
    'GPIOR2||TACH10':
      PIN_NUMBER='(0,0,0,V24,0,0)';
      BIDIRECTIONAL='TRUE';
      INPUT_LOAD='(-0.01,0.01)';
      OUTPUT_LOAD='(1.0,-1.0)';
      PINUSE='BI';
    'GPIOR3||TACH11':
      PIN_NUMBER='(0,0,0,V26,0,0)';
      BIDIRECTIONAL='TRUE';
      INPUT_LOAD='(-0.01,0.01)';
      OUTPUT_LOAD='(1.0,-1.0)';
      PINUSE='BI';
    'GPIOR4||TACH12':
      PIN_NUMBER='(0,0,0,U25,0,0)';
      BIDIRECTIONAL='TRUE';
      INPUT_LOAD='(-0.01,0.01)';
      OUTPUT_LOAD='(1.0,-1.0)';
      PINUSE='BI';
    'GPIOR5||TACH13':
      PIN_NUMBER='(0,0,0,T23,0,0)';
      BIDIRECTIONAL='TRUE';
      INPUT_LOAD='(-0.01,0.01)';
      OUTPUT_LOAD='(1.0,-1.0)';
      PINUSE='BI';
    'GPIOR6||TACH14':
      PIN_NUMBER='(0,0,0,W26,0,0)';
      BIDIRECTIONAL='TRUE';
      INPUT_LOAD='(-0.01,0.01)';
      OUTPUT_LOAD='(1.0,-1.0)';
      PINUSE='BI';
    'GPIOR7||TACH15':
      PIN_NUMBER='(0,0,0,U26,0,0)';
      BIDIRECTIONAL='TRUE';
      INPUT_LOAD='(-0.01,0.01)';
      OUTPUT_LOAD='(1.0,-1.0)';
      PINUSE='BI';
    'GPIOP0||PWM8||THRUIN0':
      PIN_NUMBER='(0,0,0,AB22,0,0)';
      BIDIRECTIONAL='TRUE';
      INPUT_LOAD='(-0.01,0.01)';
      OUTPUT_LOAD='(1.0,-1.0)';
      PINUSE='BI';
    'GPIOP1||PWM9||THRUOUT0':
      PIN_NUMBER='(0,0,0,W24,0,0)';
      BIDIRECTIONAL='TRUE';
      INPUT_LOAD='(-0.01,0.01)';
      OUTPUT_LOAD='(1.0,-1.0)';
      PINUSE='BI';
    'GPIOP2||PWM10||THRUIN1':
      PIN_NUMBER='(0,0,0,AA23,0,0)';
      BIDIRECTIONAL='TRUE';
      INPUT_LOAD='(-0.01,0.01)';
      OUTPUT_LOAD='(1.0,-1.0)';
      PINUSE='BI';
    'GPIOP3||PWM11||THRUOUT1':
      PIN_NUMBER='(0,0,0,AA24,0,0)';
      BIDIRECTIONAL='TRUE';
      INPUT_LOAD='(-0.01,0.01)';
      OUTPUT_LOAD='(1.0,-1.0)';
      PINUSE='BI';
    'GPIOP4||PWM12||THRUIN2':
      PIN_NUMBER='(0,0,0,W23,0,0)';
      BIDIRECTIONAL='TRUE';
      INPUT_LOAD='(-0.01,0.01)';
      OUTPUT_LOAD='(1.0,-1.0)';
      PINUSE='BI';
    'GPIOP5||PWM13||THRUOUT2':
      PIN_NUMBER='(0,0,0,AB23,0,0)';
      BIDIRECTIONAL='TRUE';
      INPUT_LOAD='(-0.01,0.01)';
      OUTPUT_LOAD='(1.0,-1.0)';
      PINUSE='BI';
    'GPIOP6||PWM14':
      PIN_NUMBER='(0,0,0,AB24,0,0)';
      BIDIRECTIONAL='TRUE';
      INPUT_LOAD='(-0.01,0.01)';
      OUTPUT_LOAD='(1.0,-1.0)';
      PINUSE='BI';
    'GPIOP7||PWM15||HBLED#':
      PIN_NUMBER='(0,0,0,Y23,0,0)';
      BIDIRECTIONAL='TRUE';
      INPUT_LOAD='(-0.01,0.01)';
      OUTPUT_LOAD='(1.0,-1.0)';
      PINUSE='BI';
    'SSPRST#':
      PIN_NUMBER='(0,0,0,D7,0,0)';
      INPUT_LOAD='(-0.01,0.01)';
      PINUSE='IN';
    'USB2AV18':
      PIN_NUMBER='(0,0,0,K10,0,0)';
      PINUSE='POWER';
      NO_LOAD_CHECK='Both';
      NO_IO_CHECK='Both';
      NO_ASSERT_CHECK='TRUE';
      NO_DIR_CHECK='TRUE';
      ALLOW_CONNECT='TRUE';
    'PECIVDD':
      PIN_NUMBER='(0,0,0,AA18,0,0)';
      PINUSE='POWER';
      NO_LOAD_CHECK='Both';
      NO_IO_CHECK='Both';
      NO_ASSERT_CHECK='TRUE';
      NO_DIR_CHECK='TRUE';
      ALLOW_CONNECT='TRUE';
    'PECI':
      PIN_NUMBER='(0,0,0,AF16,0,0)';
      BIDIRECTIONAL='TRUE';
      INPUT_LOAD='(-0.01,0.01)';
      OUTPUT_LOAD='(1.0,-1.0)';
      PINUSE='BI';
    'GPIOI4||MTDO2':
      PIN_NUMBER='(0,0,0,C16,0,0)';
      BIDIRECTIONAL='TRUE';
      INPUT_LOAD='(-0.01,0.01)';
      OUTPUT_LOAD='(1.0,-1.0)';
      PINUSE='BI';
    'GPIOI3||MTMS2||RXD13':
      PIN_NUMBER='(0,0,0,D16,0,0)';
      BIDIRECTIONAL='TRUE';
      INPUT_LOAD='(-0.01,0.01)';
      OUTPUT_LOAD='(1.0,-1.0)';
      PINUSE='BI';
    'GPIOI2||MTCK2||TXD13':
      PIN_NUMBER='(0,0,0,E17,0,0)';
      BIDIRECTIONAL='TRUE';
      INPUT_LOAD='(-0.01,0.01)';
      OUTPUT_LOAD='(1.0,-1.0)';
      PINUSE='BI';
    'GPIOI0||MNTRST2||TXD12':
      PIN_NUMBER='(0,0,0,D17,0,0)';
      BIDIRECTIONAL='TRUE';
      INPUT_LOAD='(-0.01,0.01)';
      OUTPUT_LOAD='(1.0,-1.0)';
      PINUSE='BI';
    'GPIOI1||MTDI2||RXD12':
      PIN_NUMBER='(0,0,0,A16,0,0)';
      BIDIRECTIONAL='TRUE';
      INPUT_LOAD='(-0.01,0.01)';
      OUTPUT_LOAD='(1.0,-1.0)';
      PINUSE='BI';
    'CHASI#':
      PIN_NUMBER='(0,0,0,AB21,0,0)';
      INPUT_LOAD='(-0.01,0.01)';
      PINUSE='IN';
    'ADCREXT0':
      PIN_NUMBER='(0,0,0,0,AF20,0)';
      OUTPUT_LOAD='(1.0,-1.0)';
      PINUSE='OUT';
    'ADCVREFN0':
      PIN_NUMBER='(0,0,0,0,AB20,0)';
      OUTPUT_LOAD='(1.0,-1.0)';
      PINUSE='OUT';
    'ADCVREFP0':
      PIN_NUMBER='(0,0,0,0,AC20,0)';
      OUTPUT_LOAD='(1.0,-1.0)';
      PINUSE='OUT';
    'ADCAV33_Y21':
      PIN_NUMBER='(0,0,0,0,Y21,0)';
      PINUSE='POWER';
      NO_LOAD_CHECK='Both';
      NO_IO_CHECK='Both';
      NO_ASSERT_CHECK='TRUE';
      NO_DIR_CHECK='TRUE';
      ALLOW_CONNECT='TRUE';
    'DACAV33_V21':
      PIN_NUMBER='(0,0,0,0,V21,0)';
      PINUSE='POWER';
      NO_LOAD_CHECK='Both';
      NO_IO_CHECK='Both';
      NO_ASSERT_CHECK='TRUE';
      NO_DIR_CHECK='TRUE';
      ALLOW_CONNECT='TRUE';
    'DACRSET':
      PIN_NUMBER='(0,0,0,0,AC21,0)';
      BIDIRECTIONAL='TRUE';
      INPUT_LOAD='(-0.01,0.01)';
      OUTPUT_LOAD='(1.0,-1.0)';
      PINUSE='BI';
    'PLLAVDD_E7':
      PIN_NUMBER='(0,0,0,0,E7,0)';
      PINUSE='POWER';
      NO_LOAD_CHECK='Both';
      NO_IO_CHECK='Both';
      NO_ASSERT_CHECK='TRUE';
      NO_DIR_CHECK='TRUE';
      ALLOW_CONNECT='TRUE';
    'PLLAHVDD':
      PIN_NUMBER='(0,0,0,0,H14,0)';
      PINUSE='POWER';
      NO_LOAD_CHECK='Both';
      NO_IO_CHECK='Both';
      NO_ASSERT_CHECK='TRUE';
      NO_DIR_CHECK='TRUE';
      ALLOW_CONNECT='TRUE';
    'ADCVREFP1':
      PIN_NUMBER='(0,0,0,0,AD17,0)';
      OUTPUT_LOAD='(1.0,-1.0)';
      PINUSE='OUT';
    'ADCVREFN1':
      PIN_NUMBER='(0,0,0,0,AD18,0)';
      OUTPUT_LOAD='(1.0,-1.0)';
      PINUSE='OUT';
    'ADCREXT1':
      PIN_NUMBER='(0,0,0,0,AF18,0)';
      OUTPUT_LOAD='(1.0,-1.0)';
      PINUSE='OUT';
    'IV10D_L9':
      PIN_NUMBER='(0,0,0,0,L9,0)';
      PINUSE='POWER';
      NO_LOAD_CHECK='Both';
      NO_IO_CHECK='Both';
      NO_ASSERT_CHECK='TRUE';
      NO_DIR_CHECK='TRUE';
      ALLOW_CONNECT='TRUE';
    'IV10D_L10':
      PIN_NUMBER='(0,0,0,0,L10,0)';
      PINUSE='POWER';
      NO_LOAD_CHECK='Both';
      NO_IO_CHECK='Both';
      NO_ASSERT_CHECK='TRUE';
      NO_DIR_CHECK='TRUE';
      ALLOW_CONNECT='TRUE';
    'IV10D_M8':
      PIN_NUMBER='(0,0,0,0,M8,0)';
      PINUSE='POWER';
      NO_LOAD_CHECK='Both';
      NO_IO_CHECK='Both';
      NO_ASSERT_CHECK='TRUE';
      NO_DIR_CHECK='TRUE';
      ALLOW_CONNECT='TRUE';
    'AVDDPLL':
      PIN_NUMBER='(0,0,0,0,N5,0)';
      PINUSE='POWER';
      NO_LOAD_CHECK='Both';
      NO_IO_CHECK='Both';
      NO_ASSERT_CHECK='TRUE';
      NO_DIR_CHECK='TRUE';
      ALLOW_CONNECT='TRUE';
    'MVDD_G6':
      PIN_NUMBER='(0,0,0,0,G6,0)';
      PINUSE='POWER';
      NO_LOAD_CHECK='Both';
      NO_IO_CHECK='Both';
      NO_ASSERT_CHECK='TRUE';
      NO_DIR_CHECK='TRUE';
      ALLOW_CONNECT='TRUE';
    'PLLAVDD_F7':
      PIN_NUMBER='(0,0,0,0,F7,0)';
      PINUSE='POWER';
      NO_LOAD_CHECK='Both';
      NO_IO_CHECK='Both';
      NO_ASSERT_CHECK='TRUE';
      NO_DIR_CHECK='TRUE';
      ALLOW_CONNECT='TRUE';
    'DACAV33_W21':
      PIN_NUMBER='(0,0,0,0,W21,0)';
      PINUSE='POWER';
      NO_LOAD_CHECK='Both';
      NO_IO_CHECK='Both';
      NO_ASSERT_CHECK='TRUE';
      NO_DIR_CHECK='TRUE';
      ALLOW_CONNECT='TRUE';
    'PLLDVDD_E9':
      PIN_NUMBER='(0,0,0,0,E9,0)';
      PINUSE='POWER';
      NO_LOAD_CHECK='Both';
      NO_IO_CHECK='Both';
      NO_ASSERT_CHECK='TRUE';
      NO_DIR_CHECK='TRUE';
      ALLOW_CONNECT='TRUE';
    'PLLDVDD_F9':
      PIN_NUMBER='(0,0,0,0,F9,0)';
      PINUSE='POWER';
      NO_LOAD_CHECK='Both';
      NO_IO_CHECK='Both';
      NO_ASSERT_CHECK='TRUE';
      NO_DIR_CHECK='TRUE';
      ALLOW_CONNECT='TRUE';
    'RC_VCC10A':
      PIN_NUMBER='(0,0,0,0,T9,0)';
      PINUSE='POWER';
      NO_LOAD_CHECK='Both';
      NO_IO_CHECK='Both';
      NO_ASSERT_CHECK='TRUE';
      NO_DIR_CHECK='TRUE';
      ALLOW_CONNECT='TRUE';
    'RC_VCC18A':
      PIN_NUMBER='(0,0,0,0,V9,0)';
      PINUSE='POWER';
      NO_LOAD_CHECK='Both';
      NO_IO_CHECK='Both';
      NO_ASSERT_CHECK='TRUE';
      NO_DIR_CHECK='TRUE';
      ALLOW_CONNECT='TRUE';
    'PE_VCC10A':
      PIN_NUMBER='(0,0,0,0,T10,0)';
      PINUSE='POWER';
      NO_LOAD_CHECK='Both';
      NO_IO_CHECK='Both';
      NO_ASSERT_CHECK='TRUE';
      NO_DIR_CHECK='TRUE';
      ALLOW_CONNECT='TRUE';
    'PE_VCC18A':
      PIN_NUMBER='(0,0,0,0,V10,0)';
      PINUSE='POWER';
      NO_LOAD_CHECK='Both';
      NO_IO_CHECK='Both';
      NO_ASSERT_CHECK='TRUE';
      NO_DIR_CHECK='TRUE';
      ALLOW_CONNECT='TRUE';
    'DP_VCC18A':
      PIN_NUMBER='(0,0,0,0,V8,0)';
      PINUSE='POWER';
      NO_LOAD_CHECK='Both';
      NO_IO_CHECK='Both';
      NO_ASSERT_CHECK='TRUE';
      NO_DIR_CHECK='TRUE';
      ALLOW_CONNECT='TRUE';
    'DP_VCC10A':
      PIN_NUMBER='(0,0,0,0,T8,0)';
      PINUSE='POWER';
      NO_LOAD_CHECK='Both';
      NO_IO_CHECK='Both';
      NO_ASSERT_CHECK='TRUE';
      NO_DIR_CHECK='TRUE';
      ALLOW_CONNECT='TRUE';
    'MVDD_H6':
      PIN_NUMBER='(0,0,0,0,H6,0)';
      PINUSE='POWER';
      NO_LOAD_CHECK='Both';
      NO_IO_CHECK='Both';
      NO_ASSERT_CHECK='TRUE';
      NO_DIR_CHECK='TRUE';
      ALLOW_CONNECT='TRUE';
    'MVDD_J6':
      PIN_NUMBER='(0,0,0,0,J6,0)';
      PINUSE='POWER';
      NO_LOAD_CHECK='Both';
      NO_IO_CHECK='Both';
      NO_ASSERT_CHECK='TRUE';
      NO_DIR_CHECK='TRUE';
      ALLOW_CONNECT='TRUE';
    'MVDD_K6':
      PIN_NUMBER='(0,0,0,0,K6,0)';
      PINUSE='POWER';
      NO_LOAD_CHECK='Both';
      NO_IO_CHECK='Both';
      NO_ASSERT_CHECK='TRUE';
      NO_DIR_CHECK='TRUE';
      ALLOW_CONNECT='TRUE';
    'MVDD_L6':
      PIN_NUMBER='(0,0,0,0,L6,0)';
      PINUSE='POWER';
      NO_LOAD_CHECK='Both';
      NO_IO_CHECK='Both';
      NO_ASSERT_CHECK='TRUE';
      NO_DIR_CHECK='TRUE';
      ALLOW_CONNECT='TRUE';
    'MVDD_P6':
      PIN_NUMBER='(0,0,0,0,P6,0)';
      PINUSE='POWER';
      NO_LOAD_CHECK='Both';
      NO_IO_CHECK='Both';
      NO_ASSERT_CHECK='TRUE';
      NO_DIR_CHECK='TRUE';
      ALLOW_CONNECT='TRUE';
    'MVDD_R6':
      PIN_NUMBER='(0,0,0,0,R6,0)';
      PINUSE='POWER';
      NO_LOAD_CHECK='Both';
      NO_IO_CHECK='Both';
      NO_ASSERT_CHECK='TRUE';
      NO_DIR_CHECK='TRUE';
      ALLOW_CONNECT='TRUE';
    'MVDD_T6':
      PIN_NUMBER='(0,0,0,0,T6,0)';
      PINUSE='POWER';
      NO_LOAD_CHECK='Both';
      NO_IO_CHECK='Both';
      NO_ASSERT_CHECK='TRUE';
      NO_DIR_CHECK='TRUE';
      ALLOW_CONNECT='TRUE';
    'MVDD_CK':
      PIN_NUMBER='(0,0,0,0,M6,0)';
      PINUSE='POWER';
      NO_LOAD_CHECK='Both';
      NO_IO_CHECK='Both';
      NO_ASSERT_CHECK='TRUE';
      NO_DIR_CHECK='TRUE';
      ALLOW_CONNECT='TRUE';
    'IV12D_K16':
      PIN_NUMBER='(0,0,0,0,K16,0)';
      PINUSE='POWER';
      NO_LOAD_CHECK='Both';
      NO_IO_CHECK='Both';
      NO_ASSERT_CHECK='TRUE';
      NO_DIR_CHECK='TRUE';
      ALLOW_CONNECT='TRUE';
    'IV12D_K17':
      PIN_NUMBER='(0,0,0,0,K17,0)';
      PINUSE='POWER';
      NO_LOAD_CHECK='Both';
      NO_IO_CHECK='Both';
      NO_ASSERT_CHECK='TRUE';
      NO_DIR_CHECK='TRUE';
      ALLOW_CONNECT='TRUE';
    'IV12D_K18':
      PIN_NUMBER='(0,0,0,0,K18,0)';
      PINUSE='POWER';
      NO_LOAD_CHECK='Both';
      NO_IO_CHECK='Both';
      NO_ASSERT_CHECK='TRUE';
      NO_DIR_CHECK='TRUE';
      ALLOW_CONNECT='TRUE';
    'IV12D_K19':
      PIN_NUMBER='(0,0,0,0,K19,0)';
      PINUSE='POWER';
      NO_LOAD_CHECK='Both';
      NO_IO_CHECK='Both';
      NO_ASSERT_CHECK='TRUE';
      NO_DIR_CHECK='TRUE';
      ALLOW_CONNECT='TRUE';
    'IV12D_L14':
      PIN_NUMBER='(0,0,0,0,L14,0)';
      PINUSE='POWER';
      NO_LOAD_CHECK='Both';
      NO_IO_CHECK='Both';
      NO_ASSERT_CHECK='TRUE';
      NO_DIR_CHECK='TRUE';
      ALLOW_CONNECT='TRUE';
    'IV12D_M14':
      PIN_NUMBER='(0,0,0,0,M14,0)';
      PINUSE='POWER';
      NO_LOAD_CHECK='Both';
      NO_IO_CHECK='Both';
      NO_ASSERT_CHECK='TRUE';
      NO_DIR_CHECK='TRUE';
      ALLOW_CONNECT='TRUE';
    'IV12D_N14':
      PIN_NUMBER='(0,0,0,0,N14,0)';
      PINUSE='POWER';
      NO_LOAD_CHECK='Both';
      NO_IO_CHECK='Both';
      NO_ASSERT_CHECK='TRUE';
      NO_DIR_CHECK='TRUE';
      ALLOW_CONNECT='TRUE';
    'IV12D_P14':
      PIN_NUMBER='(0,0,0,0,P14,0)';
      PINUSE='POWER';
      NO_LOAD_CHECK='Both';
      NO_IO_CHECK='Both';
      NO_ASSERT_CHECK='TRUE';
      NO_DIR_CHECK='TRUE';
      ALLOW_CONNECT='TRUE';
    'IV12D_R14':
      PIN_NUMBER='(0,0,0,0,R14,0)';
      PINUSE='POWER';
      NO_LOAD_CHECK='Both';
      NO_IO_CHECK='Both';
      NO_ASSERT_CHECK='TRUE';
      NO_DIR_CHECK='TRUE';
      ALLOW_CONNECT='TRUE';
    'IV12D_T14':
      PIN_NUMBER='(0,0,0,0,T14,0)';
      PINUSE='POWER';
      NO_LOAD_CHECK='Both';
      NO_IO_CHECK='Both';
      NO_ASSERT_CHECK='TRUE';
      NO_DIR_CHECK='TRUE';
      ALLOW_CONNECT='TRUE';
    'IV12D_L21':
      PIN_NUMBER='(0,0,0,0,L21,0)';
      PINUSE='POWER';
      NO_LOAD_CHECK='Both';
      NO_IO_CHECK='Both';
      NO_ASSERT_CHECK='TRUE';
      NO_DIR_CHECK='TRUE';
      ALLOW_CONNECT='TRUE';
    'IV12D_M21':
      PIN_NUMBER='(0,0,0,0,M21,0)';
      PINUSE='POWER';
      NO_LOAD_CHECK='Both';
      NO_IO_CHECK='Both';
      NO_ASSERT_CHECK='TRUE';
      NO_DIR_CHECK='TRUE';
      ALLOW_CONNECT='TRUE';
    'IV12D_N21':
      PIN_NUMBER='(0,0,0,0,N21,0)';
      PINUSE='POWER';
      NO_LOAD_CHECK='Both';
      NO_IO_CHECK='Both';
      NO_ASSERT_CHECK='TRUE';
      NO_DIR_CHECK='TRUE';
      ALLOW_CONNECT='TRUE';
    'IV12D_P21':
      PIN_NUMBER='(0,0,0,0,P21,0)';
      PINUSE='POWER';
      NO_LOAD_CHECK='Both';
      NO_IO_CHECK='Both';
      NO_ASSERT_CHECK='TRUE';
      NO_DIR_CHECK='TRUE';
      ALLOW_CONNECT='TRUE';
    'IV12D_R21':
      PIN_NUMBER='(0,0,0,0,R21,0)';
      PINUSE='POWER';
      NO_LOAD_CHECK='Both';
      NO_IO_CHECK='Both';
      NO_ASSERT_CHECK='TRUE';
      NO_DIR_CHECK='TRUE';
      ALLOW_CONNECT='TRUE';
    'IV12D_T21':
      PIN_NUMBER='(0,0,0,0,T21,0)';
      PINUSE='POWER';
      NO_LOAD_CHECK='Both';
      NO_IO_CHECK='Both';
      NO_ASSERT_CHECK='TRUE';
      NO_DIR_CHECK='TRUE';
      ALLOW_CONNECT='TRUE';
    'IV12D_U15':
      PIN_NUMBER='(0,0,0,0,U15,0)';
      PINUSE='POWER';
      NO_LOAD_CHECK='Both';
      NO_IO_CHECK='Both';
      NO_ASSERT_CHECK='TRUE';
      NO_DIR_CHECK='TRUE';
      ALLOW_CONNECT='TRUE';
    'IV12D_U16':
      PIN_NUMBER='(0,0,0,0,U16,0)';
      PINUSE='POWER';
      NO_LOAD_CHECK='Both';
      NO_IO_CHECK='Both';
      NO_ASSERT_CHECK='TRUE';
      NO_DIR_CHECK='TRUE';
      ALLOW_CONNECT='TRUE';
    'IV12D_U17':
      PIN_NUMBER='(0,0,0,0,U17,0)';
      PINUSE='POWER';
      NO_LOAD_CHECK='Both';
      NO_IO_CHECK='Both';
      NO_ASSERT_CHECK='TRUE';
      NO_DIR_CHECK='TRUE';
      ALLOW_CONNECT='TRUE';
    'IV12D_U18':
      PIN_NUMBER='(0,0,0,0,U18,0)';
      PINUSE='POWER';
      NO_LOAD_CHECK='Both';
      NO_IO_CHECK='Both';
      NO_ASSERT_CHECK='TRUE';
      NO_DIR_CHECK='TRUE';
      ALLOW_CONNECT='TRUE';
    'RVDD_L22':
      PIN_NUMBER='(0,0,0,0,L22,0)';
      PINUSE='POWER';
      NO_LOAD_CHECK='Both';
      NO_IO_CHECK='Both';
      NO_ASSERT_CHECK='TRUE';
      NO_DIR_CHECK='TRUE';
      ALLOW_CONNECT='TRUE';
    'RVDD_M22':
      PIN_NUMBER='(0,0,0,0,M22,0)';
      PINUSE='POWER';
      NO_LOAD_CHECK='Both';
      NO_IO_CHECK='Both';
      NO_ASSERT_CHECK='TRUE';
      NO_DIR_CHECK='TRUE';
      ALLOW_CONNECT='TRUE';
    'RVDD_J21':
      PIN_NUMBER='(0,0,0,0,J21,0)';
      PINUSE='POWER';
      NO_LOAD_CHECK='Both';
      NO_IO_CHECK='Both';
      NO_ASSERT_CHECK='TRUE';
      NO_DIR_CHECK='TRUE';
      ALLOW_CONNECT='TRUE';
    'RVDD_K21':
      PIN_NUMBER='(0,0,0,0,K21,0)';
      PINUSE='POWER';
      NO_LOAD_CHECK='Both';
      NO_IO_CHECK='Both';
      NO_ASSERT_CHECK='TRUE';
      NO_DIR_CHECK='TRUE';
      ALLOW_CONNECT='TRUE';
    'SD1VDD_G21':
      PIN_NUMBER='(0,0,0,0,G21,0)';
      PINUSE='POWER';
      NO_LOAD_CHECK='Both';
      NO_IO_CHECK='Both';
      NO_ASSERT_CHECK='TRUE';
      NO_DIR_CHECK='TRUE';
      ALLOW_CONNECT='TRUE';
    'SD2VDD_H18':
      PIN_NUMBER='(0,0,0,0,H18,0)';
      PINUSE='POWER';
      NO_LOAD_CHECK='Both';
      NO_IO_CHECK='Both';
      NO_ASSERT_CHECK='TRUE';
      NO_DIR_CHECK='TRUE';
      ALLOW_CONNECT='TRUE';
    'LPVDD':
      PIN_NUMBER='(0,0,0,0,W15,0)';
      PINUSE='POWER';
      NO_LOAD_CHECK='Both';
      NO_IO_CHECK='Both';
      NO_ASSERT_CHECK='TRUE';
      NO_DIR_CHECK='TRUE';
      ALLOW_CONNECT='TRUE';
    'I3CVDDH_F19':
      PIN_NUMBER='(0,0,0,0,F19,0)';
      PINUSE='POWER';
      NO_LOAD_CHECK='Both';
      NO_IO_CHECK='Both';
      NO_ASSERT_CHECK='TRUE';
      NO_DIR_CHECK='TRUE';
      ALLOW_CONNECT='TRUE';
    'IV10D_N8':
      PIN_NUMBER='(0,0,0,0,N8,0)';
      PINUSE='POWER';
      NO_LOAD_CHECK='Both';
      NO_IO_CHECK='Both';
      NO_ASSERT_CHECK='TRUE';
      NO_DIR_CHECK='TRUE';
      ALLOW_CONNECT='TRUE';
    'IV10D_P8':
      PIN_NUMBER='(0,0,0,0,P8,0)';
      PINUSE='POWER';
      NO_LOAD_CHECK='Both';
      NO_IO_CHECK='Both';
      NO_ASSERT_CHECK='TRUE';
      NO_DIR_CHECK='TRUE';
      ALLOW_CONNECT='TRUE';
    'IV10D_M11':
      PIN_NUMBER='(0,0,0,0,M11,0)';
      PINUSE='POWER';
      NO_LOAD_CHECK='Both';
      NO_IO_CHECK='Both';
      NO_ASSERT_CHECK='TRUE';
      NO_DIR_CHECK='TRUE';
      ALLOW_CONNECT='TRUE';
    'IV10D_N11':
      PIN_NUMBER='(0,0,0,0,N11,0)';
      PINUSE='POWER';
      NO_LOAD_CHECK='Both';
      NO_IO_CHECK='Both';
      NO_ASSERT_CHECK='TRUE';
      NO_DIR_CHECK='TRUE';
      ALLOW_CONNECT='TRUE';
    'IV10D_P11':
      PIN_NUMBER='(0,0,0,0,P11,0)';
      PINUSE='POWER';
      NO_LOAD_CHECK='Both';
      NO_IO_CHECK='Both';
      NO_ASSERT_CHECK='TRUE';
      NO_DIR_CHECK='TRUE';
      ALLOW_CONNECT='TRUE';
    'IV10D_R9':
      PIN_NUMBER='(0,0,0,0,R9,0)';
      PINUSE='POWER';
      NO_LOAD_CHECK='Both';
      NO_IO_CHECK='Both';
      NO_ASSERT_CHECK='TRUE';
      NO_DIR_CHECK='TRUE';
      ALLOW_CONNECT='TRUE';
    'PV18D_U6':
      PIN_NUMBER='(0,0,0,0,U6,0)';
      PINUSE='POWER';
      NO_LOAD_CHECK='Both';
      NO_IO_CHECK='Both';
      NO_ASSERT_CHECK='TRUE';
      NO_DIR_CHECK='TRUE';
      ALLOW_CONNECT='TRUE';
    'PV18D_V6':
      PIN_NUMBER='(0,0,0,0,V6,0)';
      PINUSE='POWER';
      NO_LOAD_CHECK='Both';
      NO_IO_CHECK='Both';
      NO_ASSERT_CHECK='TRUE';
      NO_DIR_CHECK='TRUE';
      ALLOW_CONNECT='TRUE';
    'PV18D_H8':
      PIN_NUMBER='(0,0,0,0,H8,0)';
      PINUSE='POWER';
      NO_LOAD_CHECK='Both';
      NO_IO_CHECK='Both';
      NO_ASSERT_CHECK='TRUE';
      NO_DIR_CHECK='TRUE';
      ALLOW_CONNECT='TRUE';
    'PV18D_J8':
      PIN_NUMBER='(0,0,0,0,J8,0)';
      PINUSE='POWER';
      NO_LOAD_CHECK='Both';
      NO_IO_CHECK='Both';
      NO_ASSERT_CHECK='TRUE';
      NO_DIR_CHECK='TRUE';
      ALLOW_CONNECT='TRUE';
    'PV18D_RGM_H12':
      PIN_NUMBER='(0,0,0,0,H12,0)';
      PINUSE='POWER';
      NO_LOAD_CHECK='Both';
      NO_IO_CHECK='Both';
      NO_ASSERT_CHECK='TRUE';
      NO_DIR_CHECK='TRUE';
      ALLOW_CONNECT='TRUE';
    'PV33D_H16':
      PIN_NUMBER='(0,0,0,0,H16,0)';
      PINUSE='POWER';
      NO_LOAD_CHECK='Both';
      NO_IO_CHECK='Both';
      NO_ASSERT_CHECK='TRUE';
      NO_DIR_CHECK='TRUE';
      ALLOW_CONNECT='TRUE';
    'PV33D_H17':
      PIN_NUMBER='(0,0,0,0,H17,0)';
      PINUSE='POWER';
      NO_LOAD_CHECK='Both';
      NO_IO_CHECK='Both';
      NO_ASSERT_CHECK='TRUE';
      NO_DIR_CHECK='TRUE';
      ALLOW_CONNECT='TRUE';
    'PV33D_W16':
      PIN_NUMBER='(0,0,0,0,W16,0)';
      PINUSE='POWER';
      NO_LOAD_CHECK='Both';
      NO_IO_CHECK='Both';
      NO_ASSERT_CHECK='TRUE';
      NO_DIR_CHECK='TRUE';
      ALLOW_CONNECT='TRUE';
    'PV33D_W17':
      PIN_NUMBER='(0,0,0,0,W17,0)';
      PINUSE='POWER';
      NO_LOAD_CHECK='Both';
      NO_IO_CHECK='Both';
      NO_ASSERT_CHECK='TRUE';
      NO_DIR_CHECK='TRUE';
      ALLOW_CONNECT='TRUE';
    'PV33D_W18':
      PIN_NUMBER='(0,0,0,0,W18,0)';
      PINUSE='POWER';
      NO_LOAD_CHECK='Both';
      NO_IO_CHECK='Both';
      NO_ASSERT_CHECK='TRUE';
      NO_DIR_CHECK='TRUE';
      ALLOW_CONNECT='TRUE';
    'PV33D_W19':
      PIN_NUMBER='(0,0,0,0,W19,0)';
      PINUSE='POWER';
      NO_LOAD_CHECK='Both';
      NO_IO_CHECK='Both';
      NO_ASSERT_CHECK='TRUE';
      NO_DIR_CHECK='TRUE';
      ALLOW_CONNECT='TRUE';
    'PV33D_N22':
      PIN_NUMBER='(0,0,0,0,N22,0)';
      PINUSE='POWER';
      NO_LOAD_CHECK='Both';
      NO_IO_CHECK='Both';
      NO_ASSERT_CHECK='TRUE';
      NO_DIR_CHECK='TRUE';
      ALLOW_CONNECT='TRUE';
    'PV33D_P22':
      PIN_NUMBER='(0,0,0,0,P22,0)';
      PINUSE='POWER';
      NO_LOAD_CHECK='Both';
      NO_IO_CHECK='Both';
      NO_ASSERT_CHECK='TRUE';
      NO_DIR_CHECK='TRUE';
      ALLOW_CONNECT='TRUE';
    'PV33D_R22':
      PIN_NUMBER='(0,0,0,0,R22,0)';
      PINUSE='POWER';
      NO_LOAD_CHECK='Both';
      NO_IO_CHECK='Both';
      NO_ASSERT_CHECK='TRUE';
      NO_DIR_CHECK='TRUE';
      ALLOW_CONNECT='TRUE';
    'PV33D_T22':
      PIN_NUMBER='(0,0,0,0,T22,0)';
      PINUSE='POWER';
      NO_LOAD_CHECK='Both';
      NO_IO_CHECK='Both';
      NO_ASSERT_CHECK='TRUE';
      NO_DIR_CHECK='TRUE';
      ALLOW_CONNECT='TRUE';
    'BATVDD':
      PIN_NUMBER='(0,0,0,0,V23,0)';
      PINUSE='POWER';
      NO_LOAD_CHECK='Both';
      NO_IO_CHECK='Both';
      NO_ASSERT_CHECK='TRUE';
      NO_DIR_CHECK='TRUE';
      ALLOW_CONNECT='TRUE';
    'PV18D_SLI_L13':
      PIN_NUMBER='(0,0,0,0,L13,0)';
      PINUSE='POWER';
      NO_LOAD_CHECK='Both';
      NO_IO_CHECK='Both';
      NO_ASSERT_CHECK='TRUE';
      NO_DIR_CHECK='TRUE';
      ALLOW_CONNECT='TRUE';
    'PV18D_SLI_M13':
      PIN_NUMBER='(0,0,0,0,M13,0)';
      PINUSE='POWER';
      NO_LOAD_CHECK='Both';
      NO_IO_CHECK='Both';
      NO_ASSERT_CHECK='TRUE';
      NO_DIR_CHECK='TRUE';
      ALLOW_CONNECT='TRUE';
    'PV18D_SLI_N13':
      PIN_NUMBER='(0,0,0,0,N13,0)';
      PINUSE='POWER';
      NO_LOAD_CHECK='Both';
      NO_IO_CHECK='Both';
      NO_ASSERT_CHECK='TRUE';
      NO_DIR_CHECK='TRUE';
      ALLOW_CONNECT='TRUE';
    'PV18D_SLI_P13':
      PIN_NUMBER='(0,0,0,0,P13,0)';
      PINUSE='POWER';
      NO_LOAD_CHECK='Both';
      NO_IO_CHECK='Both';
      NO_ASSERT_CHECK='TRUE';
      NO_DIR_CHECK='TRUE';
      ALLOW_CONNECT='TRUE';
    'PV18D_SLI_R13':
      PIN_NUMBER='(0,0,0,0,R13,0)';
      PINUSE='POWER';
      NO_LOAD_CHECK='Both';
      NO_IO_CHECK='Both';
      NO_ASSERT_CHECK='TRUE';
      NO_DIR_CHECK='TRUE';
      ALLOW_CONNECT='TRUE';
    'PV18D_SLI_T13':
      PIN_NUMBER='(0,0,0,0,T13,0)';
      PINUSE='POWER';
      NO_LOAD_CHECK='Both';
      NO_IO_CHECK='Both';
      NO_ASSERT_CHECK='TRUE';
      NO_DIR_CHECK='TRUE';
      ALLOW_CONNECT='TRUE';
    'PV18D_SLI_U13':
      PIN_NUMBER='(0,0,0,0,U13,0)';
      PINUSE='POWER';
      NO_LOAD_CHECK='Both';
      NO_IO_CHECK='Both';
      NO_ASSERT_CHECK='TRUE';
      NO_DIR_CHECK='TRUE';
      ALLOW_CONNECT='TRUE';
    'PV18D_SLI_V13':
      PIN_NUMBER='(0,0,0,0,V13,0)';
      PINUSE='POWER';
      NO_LOAD_CHECK='Both';
      NO_IO_CHECK='Both';
      NO_ASSERT_CHECK='TRUE';
      NO_DIR_CHECK='TRUE';
      ALLOW_CONNECT='TRUE';
    'PV18D_SLI_W13':
      PIN_NUMBER='(0,0,0,0,W13,0)';
      PINUSE='POWER';
      NO_LOAD_CHECK='Both';
      NO_IO_CHECK='Both';
      NO_ASSERT_CHECK='TRUE';
      NO_DIR_CHECK='TRUE';
      ALLOW_CONNECT='TRUE';
    'PV18D_SLI_W14':
      PIN_NUMBER='(0,0,0,0,W14,0)';
      PINUSE='POWER';
      NO_LOAD_CHECK='Both';
      NO_IO_CHECK='Both';
      NO_ASSERT_CHECK='TRUE';
      NO_DIR_CHECK='TRUE';
      ALLOW_CONNECT='TRUE';
    'ADCAV33_AA21':
      PIN_NUMBER='(0,0,0,0,AA21,0)';
      PINUSE='POWER';
      NO_LOAD_CHECK='Both';
      NO_IO_CHECK='Both';
      NO_ASSERT_CHECK='TRUE';
      NO_DIR_CHECK='TRUE';
      ALLOW_CONNECT='TRUE';
    'PV18D_RGM_J12':
      PIN_NUMBER='(0,0,0,0,J12,0)';
      PINUSE='POWER';
      NO_LOAD_CHECK='Both';
      NO_IO_CHECK='Both';
      NO_ASSERT_CHECK='TRUE';
      NO_DIR_CHECK='TRUE';
      ALLOW_CONNECT='TRUE';
    'IV10D_R10':
      PIN_NUMBER='(0,0,0,0,R10,0)';
      PINUSE='POWER';
      NO_LOAD_CHECK='Both';
      NO_IO_CHECK='Both';
      NO_ASSERT_CHECK='TRUE';
      NO_DIR_CHECK='TRUE';
      ALLOW_CONNECT='TRUE';
    'ADCVREFEXT0':
      PIN_NUMBER='(0,0,0,0,AF19,0)';
      PINUSE='POWER';
      NO_LOAD_CHECK='Both';
      NO_IO_CHECK='Both';
      NO_ASSERT_CHECK='TRUE';
      NO_DIR_CHECK='TRUE';
      ALLOW_CONNECT='TRUE';
    'ADCVREFEXT1':
      PIN_NUMBER='(0,0,0,0,AF17,0)';
      PINUSE='POWER';
      NO_LOAD_CHECK='Both';
      NO_IO_CHECK='Both';
      NO_ASSERT_CHECK='TRUE';
      NO_DIR_CHECK='TRUE';
      ALLOW_CONNECT='TRUE';
    'PV18D_N12':
      PIN_NUMBER='(0,0,0,0,N12,0)';
      PINUSE='POWER';
      NO_LOAD_CHECK='Both';
      NO_IO_CHECK='Both';
      NO_ASSERT_CHECK='TRUE';
      NO_DIR_CHECK='TRUE';
      ALLOW_CONNECT='TRUE';
    'PV18D_P12':
      PIN_NUMBER='(0,0,0,0,P12,0)';
      PINUSE='POWER';
      NO_LOAD_CHECK='Both';
      NO_IO_CHECK='Both';
      NO_ASSERT_CHECK='TRUE';
      NO_DIR_CHECK='TRUE';
      ALLOW_CONNECT='TRUE';
    'PV18D_R12':
      PIN_NUMBER='(0,0,0,0,R12,0)';
      PINUSE='POWER';
      NO_LOAD_CHECK='Both';
      NO_IO_CHECK='Both';
      NO_ASSERT_CHECK='TRUE';
      NO_DIR_CHECK='TRUE';
      ALLOW_CONNECT='TRUE';
    'SD1VDD_H21':
      PIN_NUMBER='(0,0,0,0,H21,0)';
      PINUSE='POWER';
      NO_LOAD_CHECK='Both';
      NO_IO_CHECK='Both';
      NO_ASSERT_CHECK='TRUE';
      NO_DIR_CHECK='TRUE';
      ALLOW_CONNECT='TRUE';
    'SD2VDD_H19':
      PIN_NUMBER='(0,0,0,0,H19,0)';
      PINUSE='POWER';
      NO_LOAD_CHECK='Both';
      NO_IO_CHECK='Both';
      NO_ASSERT_CHECK='TRUE';
      NO_DIR_CHECK='TRUE';
      ALLOW_CONNECT='TRUE';
    'I3CVDDH_F20':
      PIN_NUMBER='(0,0,0,0,F20,0)';
      PINUSE='POWER';
      NO_LOAD_CHECK='Both';
      NO_IO_CHECK='Both';
      NO_ASSERT_CHECK='TRUE';
      NO_DIR_CHECK='TRUE';
      ALLOW_CONNECT='TRUE';
    'PV33D_H15':
      PIN_NUMBER='(0,0,0,0,H15,0)';
      PINUSE='POWER';
      NO_LOAD_CHECK='Both';
      NO_IO_CHECK='Both';
      NO_ASSERT_CHECK='TRUE';
      NO_DIR_CHECK='TRUE';
      ALLOW_CONNECT='TRUE';
    'DPLLAVDD':
      PIN_NUMBER='(0,0,0,0,J9,0)';
      PINUSE='POWER';
      NO_LOAD_CHECK='Both';
      NO_IO_CHECK='Both';
      NO_ASSERT_CHECK='TRUE';
      NO_DIR_CHECK='TRUE';
      ALLOW_CONNECT='TRUE';
    'I3CVDDL1':
      PIN_NUMBER='(0,0,0,0,V22,0)';
      PINUSE='POWER';
      NO_LOAD_CHECK='Both';
      NO_IO_CHECK='Both';
      NO_ASSERT_CHECK='TRUE';
      NO_DIR_CHECK='TRUE';
      ALLOW_CONNECT='TRUE';
    'I3CVDDL2':
      PIN_NUMBER='(0,0,0,0,U21,0)';
      PINUSE='POWER';
      NO_LOAD_CHECK='Both';
      NO_IO_CHECK='Both';
      NO_ASSERT_CHECK='TRUE';
      NO_DIR_CHECK='TRUE';
      ALLOW_CONNECT='TRUE';
    'PV33D_RGM_K11':
      PIN_NUMBER='(0,0,0,0,K11,0)';
      PINUSE='POWER';
      NO_LOAD_CHECK='Both';
      NO_IO_CHECK='Both';
      NO_ASSERT_CHECK='TRUE';
      NO_DIR_CHECK='TRUE';
      ALLOW_CONNECT='TRUE';
    'PV33D_RGM_K12':
      PIN_NUMBER='(0,0,0,0,K12,0)';
      PINUSE='POWER';
      NO_LOAD_CHECK='Both';
      NO_IO_CHECK='Both';
      NO_ASSERT_CHECK='TRUE';
      NO_DIR_CHECK='TRUE';
      ALLOW_CONNECT='TRUE';
    'GND_A1':
      PIN_NUMBER='(0,0,0,0,0,A1)';
      PINUSE='POWER';
      NO_LOAD_CHECK='Both';
      NO_IO_CHECK='Both';
      NO_ASSERT_CHECK='TRUE';
      NO_DIR_CHECK='TRUE';
      ALLOW_CONNECT='TRUE';
    'GND_A5':
      PIN_NUMBER='(0,0,0,0,0,A5)';
      PINUSE='POWER';
      NO_LOAD_CHECK='Both';
      NO_IO_CHECK='Both';
      NO_ASSERT_CHECK='TRUE';
      NO_DIR_CHECK='TRUE';
      ALLOW_CONNECT='TRUE';
    'GND_A26':
      PIN_NUMBER='(0,0,0,0,0,A26)';
      PINUSE='POWER';
      NO_LOAD_CHECK='Both';
      NO_IO_CHECK='Both';
      NO_ASSERT_CHECK='TRUE';
      NO_DIR_CHECK='TRUE';
      ALLOW_CONNECT='TRUE';
    'GND_B5':
      PIN_NUMBER='(0,0,0,0,0,B5)';
      PINUSE='POWER';
      NO_LOAD_CHECK='Both';
      NO_IO_CHECK='Both';
      NO_ASSERT_CHECK='TRUE';
      NO_DIR_CHECK='TRUE';
      ALLOW_CONNECT='TRUE';
    'GND_B11':
      PIN_NUMBER='(0,0,0,0,0,B11)';
      PINUSE='POWER';
      NO_LOAD_CHECK='Both';
      NO_IO_CHECK='Both';
      NO_ASSERT_CHECK='TRUE';
      NO_DIR_CHECK='TRUE';
      ALLOW_CONNECT='TRUE';
    'GND_B15':
      PIN_NUMBER='(0,0,0,0,0,B15)';
      PINUSE='POWER';
      NO_LOAD_CHECK='Both';
      NO_IO_CHECK='Both';
      NO_ASSERT_CHECK='TRUE';
      NO_DIR_CHECK='TRUE';
      ALLOW_CONNECT='TRUE';
    'GND_B19':
      PIN_NUMBER='(0,0,0,0,0,B19)';
      PINUSE='POWER';
      NO_LOAD_CHECK='Both';
      NO_IO_CHECK='Both';
      NO_ASSERT_CHECK='TRUE';
      NO_DIR_CHECK='TRUE';
      ALLOW_CONNECT='TRUE';
    'GND_B23':
      PIN_NUMBER='(0,0,0,0,0,B23)';
      PINUSE='POWER';
      NO_LOAD_CHECK='Both';
      NO_IO_CHECK='Both';
      NO_ASSERT_CHECK='TRUE';
      NO_DIR_CHECK='TRUE';
      ALLOW_CONNECT='TRUE';
    'GND_C3':
      PIN_NUMBER='(0,0,0,0,0,C3)';
      PINUSE='POWER';
      NO_LOAD_CHECK='Both';
      NO_IO_CHECK='Both';
      NO_ASSERT_CHECK='TRUE';
      NO_DIR_CHECK='TRUE';
      ALLOW_CONNECT='TRUE';
    'GND_D25':
      PIN_NUMBER='(0,0,0,0,0,D25)';
      PINUSE='POWER';
      NO_LOAD_CHECK='Both';
      NO_IO_CHECK='Both';
      NO_ASSERT_CHECK='TRUE';
      NO_DIR_CHECK='TRUE';
      ALLOW_CONNECT='TRUE';
    'GND_E8':
      PIN_NUMBER='(0,0,0,0,0,E8)';
      PINUSE='POWER';
      NO_LOAD_CHECK='Both';
      NO_IO_CHECK='Both';
      NO_ASSERT_CHECK='TRUE';
      NO_DIR_CHECK='TRUE';
      ALLOW_CONNECT='TRUE';
    'GND_F6':
      PIN_NUMBER='(0,0,0,0,0,F6)';
      PINUSE='POWER';
      NO_LOAD_CHECK='Both';
      NO_IO_CHECK='Both';
      NO_ASSERT_CHECK='TRUE';
      NO_DIR_CHECK='TRUE';
      ALLOW_CONNECT='TRUE';
    'GND_F8':
      PIN_NUMBER='(0,0,0,0,0,F8)';
      PINUSE='POWER';
      NO_LOAD_CHECK='Both';
      NO_IO_CHECK='Both';
      NO_ASSERT_CHECK='TRUE';
      NO_DIR_CHECK='TRUE';
      ALLOW_CONNECT='TRUE';
    'GND_F10':
      PIN_NUMBER='(0,0,0,0,0,F10)';
      PINUSE='POWER';
      NO_LOAD_CHECK='Both';
      NO_IO_CHECK='Both';
      NO_ASSERT_CHECK='TRUE';
      NO_DIR_CHECK='TRUE';
      ALLOW_CONNECT='TRUE';
    'GND_F12':
      PIN_NUMBER='(0,0,0,0,0,F12)';
      PINUSE='POWER';
      NO_LOAD_CHECK='Both';
      NO_IO_CHECK='Both';
      NO_ASSERT_CHECK='TRUE';
      NO_DIR_CHECK='TRUE';
      ALLOW_CONNECT='TRUE';
    'GND_F14':
      PIN_NUMBER='(0,0,0,0,0,F14)';
      PINUSE='POWER';
      NO_LOAD_CHECK='Both';
      NO_IO_CHECK='Both';
      NO_ASSERT_CHECK='TRUE';
      NO_DIR_CHECK='TRUE';
      ALLOW_CONNECT='TRUE';
    'GND_F16':
      PIN_NUMBER='(0,0,0,0,0,F16)';
      PINUSE='POWER';
      NO_LOAD_CHECK='Both';
      NO_IO_CHECK='Both';
      NO_ASSERT_CHECK='TRUE';
      NO_DIR_CHECK='TRUE';
      ALLOW_CONNECT='TRUE';
    'GND_F17':
      PIN_NUMBER='(0,0,0,0,0,F17)';
      PINUSE='POWER';
      NO_LOAD_CHECK='Both';
      NO_IO_CHECK='Both';
      NO_ASSERT_CHECK='TRUE';
      NO_DIR_CHECK='TRUE';
      ALLOW_CONNECT='TRUE';
    'GND_F18':
      PIN_NUMBER='(0,0,0,0,0,F18)';
      PINUSE='POWER';
      NO_LOAD_CHECK='Both';
      NO_IO_CHECK='Both';
      NO_ASSERT_CHECK='TRUE';
      NO_DIR_CHECK='TRUE';
      ALLOW_CONNECT='TRUE';
    'GND_F21':
      PIN_NUMBER='(0,0,0,0,0,F21)';
      PINUSE='POWER';
      NO_LOAD_CHECK='Both';
      NO_IO_CHECK='Both';
      NO_ASSERT_CHECK='TRUE';
      NO_DIR_CHECK='TRUE';
      ALLOW_CONNECT='TRUE';
    'GND_G2':
      PIN_NUMBER='(0,0,0,0,0,G2)';
      PINUSE='POWER';
      NO_LOAD_CHECK='Both';
      NO_IO_CHECK='Both';
      NO_ASSERT_CHECK='TRUE';
      NO_DIR_CHECK='TRUE';
      ALLOW_CONNECT='TRUE';
    'GND_G25':
      PIN_NUMBER='(0,0,0,0,0,G25)';
      PINUSE='POWER';
      NO_LOAD_CHECK='Both';
      NO_IO_CHECK='Both';
      NO_ASSERT_CHECK='TRUE';
      NO_DIR_CHECK='TRUE';
      ALLOW_CONNECT='TRUE';
    'GND_H4':
      PIN_NUMBER='(0,0,0,0,0,H4)';
      PINUSE='POWER';
      NO_LOAD_CHECK='Both';
      NO_IO_CHECK='Both';
      NO_ASSERT_CHECK='TRUE';
      NO_DIR_CHECK='TRUE';
      ALLOW_CONNECT='TRUE';
    'GND_H9':
      PIN_NUMBER='(0,0,0,0,0,H9)';
      PINUSE='POWER';
      NO_LOAD_CHECK='Both';
      NO_IO_CHECK='Both';
      NO_ASSERT_CHECK='TRUE';
      NO_DIR_CHECK='TRUE';
      ALLOW_CONNECT='TRUE';
    'GND_H10':
      PIN_NUMBER='(0,0,0,0,0,H10)';
      PINUSE='POWER';
      NO_LOAD_CHECK='Both';
      NO_IO_CHECK='Both';
      NO_ASSERT_CHECK='TRUE';
      NO_DIR_CHECK='TRUE';
      ALLOW_CONNECT='TRUE';
    'GND_H11':
      PIN_NUMBER='(0,0,0,0,0,H11)';
      PINUSE='POWER';
      NO_LOAD_CHECK='Both';
      NO_IO_CHECK='Both';
      NO_ASSERT_CHECK='TRUE';
      NO_DIR_CHECK='TRUE';
      ALLOW_CONNECT='TRUE';
    'GND_H13':
      PIN_NUMBER='(0,0,0,0,0,H13)';
      PINUSE='POWER';
      NO_LOAD_CHECK='Both';
      NO_IO_CHECK='Both';
      NO_ASSERT_CHECK='TRUE';
      NO_DIR_CHECK='TRUE';
      ALLOW_CONNECT='TRUE';
    'GND_J2':
      PIN_NUMBER='(0,0,0,0,0,J2)';
      PINUSE='POWER';
      NO_LOAD_CHECK='Both';
      NO_IO_CHECK='Both';
      NO_ASSERT_CHECK='TRUE';
      NO_DIR_CHECK='TRUE';
      ALLOW_CONNECT='TRUE';
    'GND_J11':
      PIN_NUMBER='(0,0,0,0,0,J11)';
      PINUSE='POWER';
      NO_LOAD_CHECK='Both';
      NO_IO_CHECK='Both';
      NO_ASSERT_CHECK='TRUE';
      NO_DIR_CHECK='TRUE';
      ALLOW_CONNECT='TRUE';
    'GND_J13':
      PIN_NUMBER='(0,0,0,0,0,J13)';
      PINUSE='POWER';
      NO_LOAD_CHECK='Both';
      NO_IO_CHECK='Both';
      NO_ASSERT_CHECK='TRUE';
      NO_DIR_CHECK='TRUE';
      ALLOW_CONNECT='TRUE';
    'GND_J14':
      PIN_NUMBER='(0,0,0,0,0,J14)';
      PINUSE='POWER';
      NO_LOAD_CHECK='Both';
      NO_IO_CHECK='Both';
      NO_ASSERT_CHECK='TRUE';
      NO_DIR_CHECK='TRUE';
      ALLOW_CONNECT='TRUE';
    'GND_J15':
      PIN_NUMBER='(0,0,0,0,0,J15)';
      PINUSE='POWER';
      NO_LOAD_CHECK='Both';
      NO_IO_CHECK='Both';
      NO_ASSERT_CHECK='TRUE';
      NO_DIR_CHECK='TRUE';
      ALLOW_CONNECT='TRUE';
    'GND_J16':
      PIN_NUMBER='(0,0,0,0,0,J16)';
      PINUSE='POWER';
      NO_LOAD_CHECK='Both';
      NO_IO_CHECK='Both';
      NO_ASSERT_CHECK='TRUE';
      NO_DIR_CHECK='TRUE';
      ALLOW_CONNECT='TRUE';
    'GND_J17':
      PIN_NUMBER='(0,0,0,0,0,J17)';
      PINUSE='POWER';
      NO_LOAD_CHECK='Both';
      NO_IO_CHECK='Both';
      NO_ASSERT_CHECK='TRUE';
      NO_DIR_CHECK='TRUE';
      ALLOW_CONNECT='TRUE';
    'GND_J18':
      PIN_NUMBER='(0,0,0,0,0,J18)';
      PINUSE='POWER';
      NO_LOAD_CHECK='Both';
      NO_IO_CHECK='Both';
      NO_ASSERT_CHECK='TRUE';
      NO_DIR_CHECK='TRUE';
      ALLOW_CONNECT='TRUE';
    'GND_J19':
      PIN_NUMBER='(0,0,0,0,0,J19)';
      PINUSE='POWER';
      NO_LOAD_CHECK='Both';
      NO_IO_CHECK='Both';
      NO_ASSERT_CHECK='TRUE';
      NO_DIR_CHECK='TRUE';
      ALLOW_CONNECT='TRUE';
    'GND_K4':
      PIN_NUMBER='(0,0,0,0,0,K4)';
      PINUSE='POWER';
      NO_LOAD_CHECK='Both';
      NO_IO_CHECK='Both';
      NO_ASSERT_CHECK='TRUE';
      NO_DIR_CHECK='TRUE';
      ALLOW_CONNECT='TRUE';
    'GND_K8':
      PIN_NUMBER='(0,0,0,0,0,K8)';
      PINUSE='POWER';
      NO_LOAD_CHECK='Both';
      NO_IO_CHECK='Both';
      NO_ASSERT_CHECK='TRUE';
      NO_DIR_CHECK='TRUE';
      ALLOW_CONNECT='TRUE';
    'GND_K9':
      PIN_NUMBER='(0,0,0,0,0,K9)';
      PINUSE='POWER';
      NO_LOAD_CHECK='Both';
      NO_IO_CHECK='Both';
      NO_ASSERT_CHECK='TRUE';
      NO_DIR_CHECK='TRUE';
      ALLOW_CONNECT='TRUE';
    'GND_K13':
      PIN_NUMBER='(0,0,0,0,0,K13)';
      PINUSE='POWER';
      NO_LOAD_CHECK='Both';
      NO_IO_CHECK='Both';
      NO_ASSERT_CHECK='TRUE';
      NO_DIR_CHECK='TRUE';
      ALLOW_CONNECT='TRUE';
    'GND_K14':
      PIN_NUMBER='(0,0,0,0,0,K14)';
      PINUSE='POWER';
      NO_LOAD_CHECK='Both';
      NO_IO_CHECK='Both';
      NO_ASSERT_CHECK='TRUE';
      NO_DIR_CHECK='TRUE';
      ALLOW_CONNECT='TRUE';
    'GND_K15':
      PIN_NUMBER='(0,0,0,0,0,K15)';
      PINUSE='POWER';
      NO_LOAD_CHECK='Both';
      NO_IO_CHECK='Both';
      NO_ASSERT_CHECK='TRUE';
      NO_DIR_CHECK='TRUE';
      ALLOW_CONNECT='TRUE';
    'GND_K22':
      PIN_NUMBER='(0,0,0,0,0,K22)';
      PINUSE='POWER';
      NO_LOAD_CHECK='Both';
      NO_IO_CHECK='Both';
      NO_ASSERT_CHECK='TRUE';
      NO_DIR_CHECK='TRUE';
      ALLOW_CONNECT='TRUE';
    'GND_L2':
      PIN_NUMBER='(0,0,0,0,0,L2)';
      PINUSE='POWER';
      NO_LOAD_CHECK='Both';
      NO_IO_CHECK='Both';
      NO_ASSERT_CHECK='TRUE';
      NO_DIR_CHECK='TRUE';
      ALLOW_CONNECT='TRUE';
    'GND_L8':
      PIN_NUMBER='(0,0,0,0,0,L8)';
      PINUSE='POWER';
      NO_LOAD_CHECK='Both';
      NO_IO_CHECK='Both';
      NO_ASSERT_CHECK='TRUE';
      NO_DIR_CHECK='TRUE';
      ALLOW_CONNECT='TRUE';
    'GND_L11':
      PIN_NUMBER='(0,0,0,0,0,L11)';
      PINUSE='POWER';
      NO_LOAD_CHECK='Both';
      NO_IO_CHECK='Both';
      NO_ASSERT_CHECK='TRUE';
      NO_DIR_CHECK='TRUE';
      ALLOW_CONNECT='TRUE';
    'GND_L12':
      PIN_NUMBER='(0,0,0,0,0,L12)';
      PINUSE='POWER';
      NO_LOAD_CHECK='Both';
      NO_IO_CHECK='Both';
      NO_ASSERT_CHECK='TRUE';
      NO_DIR_CHECK='TRUE';
      ALLOW_CONNECT='TRUE';
    'GND_L15':
      PIN_NUMBER='(0,0,0,0,0,L15)';
      PINUSE='POWER';
      NO_LOAD_CHECK='Both';
      NO_IO_CHECK='Both';
      NO_ASSERT_CHECK='TRUE';
      NO_DIR_CHECK='TRUE';
      ALLOW_CONNECT='TRUE';
    'GND_L16':
      PIN_NUMBER='(0,0,0,0,0,L16)';
      PINUSE='POWER';
      NO_LOAD_CHECK='Both';
      NO_IO_CHECK='Both';
      NO_ASSERT_CHECK='TRUE';
      NO_DIR_CHECK='TRUE';
      ALLOW_CONNECT='TRUE';
    'GND_L17':
      PIN_NUMBER='(0,0,0,0,0,L17)';
      PINUSE='POWER';
      NO_LOAD_CHECK='Both';
      NO_IO_CHECK='Both';
      NO_ASSERT_CHECK='TRUE';
      NO_DIR_CHECK='TRUE';
      ALLOW_CONNECT='TRUE';
    'GND_R2':
      PIN_NUMBER='(0,0,0,0,0,R2)';
      PINUSE='POWER';
      NO_LOAD_CHECK='Both';
      NO_IO_CHECK='Both';
      NO_ASSERT_CHECK='TRUE';
      NO_DIR_CHECK='TRUE';
      ALLOW_CONNECT='TRUE';
    'GND_R8':
      PIN_NUMBER='(0,0,0,0,0,R8)';
      PINUSE='POWER';
      NO_LOAD_CHECK='Both';
      NO_IO_CHECK='Both';
      NO_ASSERT_CHECK='TRUE';
      NO_DIR_CHECK='TRUE';
      ALLOW_CONNECT='TRUE';
    'GND_R11':
      PIN_NUMBER='(0,0,0,0,0,R11)';
      PINUSE='POWER';
      NO_LOAD_CHECK='Both';
      NO_IO_CHECK='Both';
      NO_ASSERT_CHECK='TRUE';
      NO_DIR_CHECK='TRUE';
      ALLOW_CONNECT='TRUE';
    'GND_R15':
      PIN_NUMBER='(0,0,0,0,0,R15)';
      PINUSE='POWER';
      NO_LOAD_CHECK='Both';
      NO_IO_CHECK='Both';
      NO_ASSERT_CHECK='TRUE';
      NO_DIR_CHECK='TRUE';
      ALLOW_CONNECT='TRUE';
    'GND_R16':
      PIN_NUMBER='(0,0,0,0,0,R16)';
      PINUSE='POWER';
      NO_LOAD_CHECK='Both';
      NO_IO_CHECK='Both';
      NO_ASSERT_CHECK='TRUE';
      NO_DIR_CHECK='TRUE';
      ALLOW_CONNECT='TRUE';
    'GND_R17':
      PIN_NUMBER='(0,0,0,0,0,R17)';
      PINUSE='POWER';
      NO_LOAD_CHECK='Both';
      NO_IO_CHECK='Both';
      NO_ASSERT_CHECK='TRUE';
      NO_DIR_CHECK='TRUE';
      ALLOW_CONNECT='TRUE';
    'GND_R18':
      PIN_NUMBER='(0,0,0,0,0,R18)';
      PINUSE='POWER';
      NO_LOAD_CHECK='Both';
      NO_IO_CHECK='Both';
      NO_ASSERT_CHECK='TRUE';
      NO_DIR_CHECK='TRUE';
      ALLOW_CONNECT='TRUE';
    'GND_R19':
      PIN_NUMBER='(0,0,0,0,0,R19)';
      PINUSE='POWER';
      NO_LOAD_CHECK='Both';
      NO_IO_CHECK='Both';
      NO_ASSERT_CHECK='TRUE';
      NO_DIR_CHECK='TRUE';
      ALLOW_CONNECT='TRUE';
    'GND_R25':
      PIN_NUMBER='(0,0,0,0,0,R25)';
      PINUSE='POWER';
      NO_LOAD_CHECK='Both';
      NO_IO_CHECK='Both';
      NO_ASSERT_CHECK='TRUE';
      NO_DIR_CHECK='TRUE';
      ALLOW_CONNECT='TRUE';
    'GND_T4':
      PIN_NUMBER='(0,0,0,0,0,T4)';
      PINUSE='POWER';
      NO_LOAD_CHECK='Both';
      NO_IO_CHECK='Both';
      NO_ASSERT_CHECK='TRUE';
      NO_DIR_CHECK='TRUE';
      ALLOW_CONNECT='TRUE';
    'GND_T11':
      PIN_NUMBER='(0,0,0,0,0,T11)';
      PINUSE='POWER';
      NO_LOAD_CHECK='Both';
      NO_IO_CHECK='Both';
      NO_ASSERT_CHECK='TRUE';
      NO_DIR_CHECK='TRUE';
      ALLOW_CONNECT='TRUE';
    'GND_T12':
      PIN_NUMBER='(0,0,0,0,0,T12)';
      PINUSE='POWER';
      NO_LOAD_CHECK='Both';
      NO_IO_CHECK='Both';
      NO_ASSERT_CHECK='TRUE';
      NO_DIR_CHECK='TRUE';
      ALLOW_CONNECT='TRUE';
    'GND_T15':
      PIN_NUMBER='(0,0,0,0,0,T15)';
      PINUSE='POWER';
      NO_LOAD_CHECK='Both';
      NO_IO_CHECK='Both';
      NO_ASSERT_CHECK='TRUE';
      NO_DIR_CHECK='TRUE';
      ALLOW_CONNECT='TRUE';
    'GND_T16':
      PIN_NUMBER='(0,0,0,0,0,T16)';
      PINUSE='POWER';
      NO_LOAD_CHECK='Both';
      NO_IO_CHECK='Both';
      NO_ASSERT_CHECK='TRUE';
      NO_DIR_CHECK='TRUE';
      ALLOW_CONNECT='TRUE';
    'GND_T17':
      PIN_NUMBER='(0,0,0,0,0,T17)';
      PINUSE='POWER';
      NO_LOAD_CHECK='Both';
      NO_IO_CHECK='Both';
      NO_ASSERT_CHECK='TRUE';
      NO_DIR_CHECK='TRUE';
      ALLOW_CONNECT='TRUE';
    'GND_T18':
      PIN_NUMBER='(0,0,0,0,0,T18)';
      PINUSE='POWER';
      NO_LOAD_CHECK='Both';
      NO_IO_CHECK='Both';
      NO_ASSERT_CHECK='TRUE';
      NO_DIR_CHECK='TRUE';
      ALLOW_CONNECT='TRUE';
    'GND_T19':
      PIN_NUMBER='(0,0,0,0,0,T19)';
      PINUSE='POWER';
      NO_LOAD_CHECK='Both';
      NO_IO_CHECK='Both';
      NO_ASSERT_CHECK='TRUE';
      NO_DIR_CHECK='TRUE';
      ALLOW_CONNECT='TRUE';
    'GND_U2':
      PIN_NUMBER='(0,0,0,0,0,U2)';
      PINUSE='POWER';
      NO_LOAD_CHECK='Both';
      NO_IO_CHECK='Both';
      NO_ASSERT_CHECK='TRUE';
      NO_DIR_CHECK='TRUE';
      ALLOW_CONNECT='TRUE';
    'GND_U8':
      PIN_NUMBER='(0,0,0,0,0,U8)';
      PINUSE='POWER';
      NO_LOAD_CHECK='Both';
      NO_IO_CHECK='Both';
      NO_ASSERT_CHECK='TRUE';
      NO_DIR_CHECK='TRUE';
      ALLOW_CONNECT='TRUE';
    'GND_U9':
      PIN_NUMBER='(0,0,0,0,0,U9)';
      PINUSE='POWER';
      NO_LOAD_CHECK='Both';
      NO_IO_CHECK='Both';
      NO_ASSERT_CHECK='TRUE';
      NO_DIR_CHECK='TRUE';
      ALLOW_CONNECT='TRUE';
    'GND_U10':
      PIN_NUMBER='(0,0,0,0,0,U10)';
      PINUSE='POWER';
      NO_LOAD_CHECK='Both';
      NO_IO_CHECK='Both';
      NO_ASSERT_CHECK='TRUE';
      NO_DIR_CHECK='TRUE';
      ALLOW_CONNECT='TRUE';
    'GND_U11':
      PIN_NUMBER='(0,0,0,0,0,U11)';
      PINUSE='POWER';
      NO_LOAD_CHECK='Both';
      NO_IO_CHECK='Both';
      NO_ASSERT_CHECK='TRUE';
      NO_DIR_CHECK='TRUE';
      ALLOW_CONNECT='TRUE';
    'GND_U12':
      PIN_NUMBER='(0,0,0,0,0,U12)';
      PINUSE='POWER';
      NO_LOAD_CHECK='Both';
      NO_IO_CHECK='Both';
      NO_ASSERT_CHECK='TRUE';
      NO_DIR_CHECK='TRUE';
      ALLOW_CONNECT='TRUE';
    'GND_U14':
      PIN_NUMBER='(0,0,0,0,0,U14)';
      PINUSE='POWER';
      NO_LOAD_CHECK='Both';
      NO_IO_CHECK='Both';
      NO_ASSERT_CHECK='TRUE';
      NO_DIR_CHECK='TRUE';
      ALLOW_CONNECT='TRUE';
    'GND_U19':
      PIN_NUMBER='(0,0,0,0,0,U19)';
      PINUSE='POWER';
      NO_LOAD_CHECK='Both';
      NO_IO_CHECK='Both';
      NO_ASSERT_CHECK='TRUE';
      NO_DIR_CHECK='TRUE';
      ALLOW_CONNECT='TRUE';
    'GND_U22':
      PIN_NUMBER='(0,0,0,0,0,U22)';
      PINUSE='POWER';
      NO_LOAD_CHECK='Both';
      NO_IO_CHECK='Both';
      NO_ASSERT_CHECK='TRUE';
      NO_DIR_CHECK='TRUE';
      ALLOW_CONNECT='TRUE';
    'GND_V5':
      PIN_NUMBER='(0,0,0,0,0,V5)';
      PINUSE='POWER';
      NO_LOAD_CHECK='Both';
      NO_IO_CHECK='Both';
      NO_ASSERT_CHECK='TRUE';
      NO_DIR_CHECK='TRUE';
      ALLOW_CONNECT='TRUE';
    'GND_V11':
      PIN_NUMBER='(0,0,0,0,0,V11)';
      PINUSE='POWER';
      NO_LOAD_CHECK='Both';
      NO_IO_CHECK='Both';
      NO_ASSERT_CHECK='TRUE';
      NO_DIR_CHECK='TRUE';
      ALLOW_CONNECT='TRUE';
    'GND_V12':
      PIN_NUMBER='(0,0,0,0,0,V12)';
      PINUSE='POWER';
      NO_LOAD_CHECK='Both';
      NO_IO_CHECK='Both';
      NO_ASSERT_CHECK='TRUE';
      NO_DIR_CHECK='TRUE';
      ALLOW_CONNECT='TRUE';
    'GND_V14':
      PIN_NUMBER='(0,0,0,0,0,V14)';
      PINUSE='POWER';
      NO_LOAD_CHECK='Both';
      NO_IO_CHECK='Both';
      NO_ASSERT_CHECK='TRUE';
      NO_DIR_CHECK='TRUE';
      ALLOW_CONNECT='TRUE';
    'GND_V15':
      PIN_NUMBER='(0,0,0,0,0,V15)';
      PINUSE='POWER';
      NO_LOAD_CHECK='Both';
      NO_IO_CHECK='Both';
      NO_ASSERT_CHECK='TRUE';
      NO_DIR_CHECK='TRUE';
      ALLOW_CONNECT='TRUE';
    'GND_V16':
      PIN_NUMBER='(0,0,0,0,0,V16)';
      PINUSE='POWER';
      NO_LOAD_CHECK='Both';
      NO_IO_CHECK='Both';
      NO_ASSERT_CHECK='TRUE';
      NO_DIR_CHECK='TRUE';
      ALLOW_CONNECT='TRUE';
    'GND_V17':
      PIN_NUMBER='(0,0,0,0,0,V17)';
      PINUSE='POWER';
      NO_LOAD_CHECK='Both';
      NO_IO_CHECK='Both';
      NO_ASSERT_CHECK='TRUE';
      NO_DIR_CHECK='TRUE';
      ALLOW_CONNECT='TRUE';
    'GND_V18':
      PIN_NUMBER='(0,0,0,0,0,V18)';
      PINUSE='POWER';
      NO_LOAD_CHECK='Both';
      NO_IO_CHECK='Both';
      NO_ASSERT_CHECK='TRUE';
      NO_DIR_CHECK='TRUE';
      ALLOW_CONNECT='TRUE';
    'GND_V19':
      PIN_NUMBER='(0,0,0,0,0,V19)';
      PINUSE='POWER';
      NO_LOAD_CHECK='Both';
      NO_IO_CHECK='Both';
      NO_ASSERT_CHECK='TRUE';
      NO_DIR_CHECK='TRUE';
      ALLOW_CONNECT='TRUE';
    'GND_W5':
      PIN_NUMBER='(0,0,0,0,0,W5)';
      PINUSE='POWER';
      NO_LOAD_CHECK='Both';
      NO_IO_CHECK='Both';
      NO_ASSERT_CHECK='TRUE';
      NO_DIR_CHECK='TRUE';
      ALLOW_CONNECT='TRUE';
    'GND_W6':
      PIN_NUMBER='(0,0,0,0,0,W6)';
      PINUSE='POWER';
      NO_LOAD_CHECK='Both';
      NO_IO_CHECK='Both';
      NO_ASSERT_CHECK='TRUE';
      NO_DIR_CHECK='TRUE';
      ALLOW_CONNECT='TRUE';
    'GND_W8':
      PIN_NUMBER='(0,0,0,0,0,W8)';
      PINUSE='POWER';
      NO_LOAD_CHECK='Both';
      NO_IO_CHECK='Both';
      NO_ASSERT_CHECK='TRUE';
      NO_DIR_CHECK='TRUE';
      ALLOW_CONNECT='TRUE';
    'GND_W9':
      PIN_NUMBER='(0,0,0,0,0,W9)';
      PINUSE='POWER';
      NO_LOAD_CHECK='Both';
      NO_IO_CHECK='Both';
      NO_ASSERT_CHECK='TRUE';
      NO_DIR_CHECK='TRUE';
      ALLOW_CONNECT='TRUE';
    'GND_W10':
      PIN_NUMBER='(0,0,0,0,0,W10)';
      PINUSE='POWER';
      NO_LOAD_CHECK='Both';
      NO_IO_CHECK='Both';
      NO_ASSERT_CHECK='TRUE';
      NO_DIR_CHECK='TRUE';
      ALLOW_CONNECT='TRUE';
    'GND_W11':
      PIN_NUMBER='(0,0,0,0,0,W11)';
      PINUSE='POWER';
      NO_LOAD_CHECK='Both';
      NO_IO_CHECK='Both';
      NO_ASSERT_CHECK='TRUE';
      NO_DIR_CHECK='TRUE';
      ALLOW_CONNECT='TRUE';
    'GND_W12':
      PIN_NUMBER='(0,0,0,0,0,W12)';
      PINUSE='POWER';
      NO_LOAD_CHECK='Both';
      NO_IO_CHECK='Both';
      NO_ASSERT_CHECK='TRUE';
      NO_DIR_CHECK='TRUE';
      ALLOW_CONNECT='TRUE';
    'GND_L18':
      PIN_NUMBER='(0,0,0,0,0,L18)';
      PINUSE='POWER';
      NO_LOAD_CHECK='Both';
      NO_IO_CHECK='Both';
      NO_ASSERT_CHECK='TRUE';
      NO_DIR_CHECK='TRUE';
      ALLOW_CONNECT='TRUE';
    'GND_L19':
      PIN_NUMBER='(0,0,0,0,0,L19)';
      PINUSE='POWER';
      NO_LOAD_CHECK='Both';
      NO_IO_CHECK='Both';
      NO_ASSERT_CHECK='TRUE';
      NO_DIR_CHECK='TRUE';
      ALLOW_CONNECT='TRUE';
    'GND_L25':
      PIN_NUMBER='(0,0,0,0,0,L25)';
      PINUSE='POWER';
      NO_LOAD_CHECK='Both';
      NO_IO_CHECK='Both';
      NO_ASSERT_CHECK='TRUE';
      NO_DIR_CHECK='TRUE';
      ALLOW_CONNECT='TRUE';
    'GND_M4':
      PIN_NUMBER='(0,0,0,0,0,M4)';
      PINUSE='POWER';
      NO_LOAD_CHECK='Both';
      NO_IO_CHECK='Both';
      NO_ASSERT_CHECK='TRUE';
      NO_DIR_CHECK='TRUE';
      ALLOW_CONNECT='TRUE';
    'GND_M9':
      PIN_NUMBER='(0,0,0,0,0,M9)';
      PINUSE='POWER';
      NO_LOAD_CHECK='Both';
      NO_IO_CHECK='Both';
      NO_ASSERT_CHECK='TRUE';
      NO_DIR_CHECK='TRUE';
      ALLOW_CONNECT='TRUE';
    'GND_M10':
      PIN_NUMBER='(0,0,0,0,0,M10)';
      PINUSE='POWER';
      NO_LOAD_CHECK='Both';
      NO_IO_CHECK='Both';
      NO_ASSERT_CHECK='TRUE';
      NO_DIR_CHECK='TRUE';
      ALLOW_CONNECT='TRUE';
    'GND_M12':
      PIN_NUMBER='(0,0,0,0,0,M12)';
      PINUSE='POWER';
      NO_LOAD_CHECK='Both';
      NO_IO_CHECK='Both';
      NO_ASSERT_CHECK='TRUE';
      NO_DIR_CHECK='TRUE';
      ALLOW_CONNECT='TRUE';
    'GND_M15':
      PIN_NUMBER='(0,0,0,0,0,M15)';
      PINUSE='POWER';
      NO_LOAD_CHECK='Both';
      NO_IO_CHECK='Both';
      NO_ASSERT_CHECK='TRUE';
      NO_DIR_CHECK='TRUE';
      ALLOW_CONNECT='TRUE';
    'GND_M16':
      PIN_NUMBER='(0,0,0,0,0,M16)';
      PINUSE='POWER';
      NO_LOAD_CHECK='Both';
      NO_IO_CHECK='Both';
      NO_ASSERT_CHECK='TRUE';
      NO_DIR_CHECK='TRUE';
      ALLOW_CONNECT='TRUE';
    'GND_M17':
      PIN_NUMBER='(0,0,0,0,0,M17)';
      PINUSE='POWER';
      NO_LOAD_CHECK='Both';
      NO_IO_CHECK='Both';
      NO_ASSERT_CHECK='TRUE';
      NO_DIR_CHECK='TRUE';
      ALLOW_CONNECT='TRUE';
    'GND_W22':
      PIN_NUMBER='(0,0,0,0,0,W22)';
      PINUSE='POWER';
      NO_LOAD_CHECK='Both';
      NO_IO_CHECK='Both';
      NO_ASSERT_CHECK='TRUE';
      NO_DIR_CHECK='TRUE';
      ALLOW_CONNECT='TRUE';
    'GND_W25':
      PIN_NUMBER='(0,0,0,0,0,W25)';
      PINUSE='POWER';
      NO_LOAD_CHECK='Both';
      NO_IO_CHECK='Both';
      NO_ASSERT_CHECK='TRUE';
      NO_DIR_CHECK='TRUE';
      ALLOW_CONNECT='TRUE';
    'GND_Y6':
      PIN_NUMBER='(0,0,0,0,0,Y6)';
      PINUSE='POWER';
      NO_LOAD_CHECK='Both';
      NO_IO_CHECK='Both';
      NO_ASSERT_CHECK='TRUE';
      NO_DIR_CHECK='TRUE';
      ALLOW_CONNECT='TRUE';
    'GND_Y22':
      PIN_NUMBER='(0,0,0,0,0,Y22)';
      PINUSE='POWER';
      NO_LOAD_CHECK='Both';
      NO_IO_CHECK='Both';
      NO_ASSERT_CHECK='TRUE';
      NO_DIR_CHECK='TRUE';
      ALLOW_CONNECT='TRUE';
    'GND_AA1':
      PIN_NUMBER='(0,0,0,0,0,AA1)';
      PINUSE='POWER';
      NO_LOAD_CHECK='Both';
      NO_IO_CHECK='Both';
      NO_ASSERT_CHECK='TRUE';
      NO_DIR_CHECK='TRUE';
      ALLOW_CONNECT='TRUE';
    'GND_AA3':
      PIN_NUMBER='(0,0,0,0,0,AA3)';
      PINUSE='POWER';
      NO_LOAD_CHECK='Both';
      NO_IO_CHECK='Both';
      NO_ASSERT_CHECK='TRUE';
      NO_DIR_CHECK='TRUE';
      ALLOW_CONNECT='TRUE';
    'GND_AA8':
      PIN_NUMBER='(0,0,0,0,0,AA8)';
      PINUSE='POWER';
      NO_LOAD_CHECK='Both';
      NO_IO_CHECK='Both';
      NO_ASSERT_CHECK='TRUE';
      NO_DIR_CHECK='TRUE';
      ALLOW_CONNECT='TRUE';
    'GND_AA7':
      PIN_NUMBER='(0,0,0,0,0,AA7)';
      PINUSE='POWER';
      NO_LOAD_CHECK='Both';
      NO_IO_CHECK='Both';
      NO_ASSERT_CHECK='TRUE';
      NO_DIR_CHECK='TRUE';
      ALLOW_CONNECT='TRUE';
    'GND_AA6':
      PIN_NUMBER='(0,0,0,0,0,AA6)';
      PINUSE='POWER';
      NO_LOAD_CHECK='Both';
      NO_IO_CHECK='Both';
      NO_ASSERT_CHECK='TRUE';
      NO_DIR_CHECK='TRUE';
      ALLOW_CONNECT='TRUE';
    'GND_M18':
      PIN_NUMBER='(0,0,0,0,0,M18)';
      PINUSE='POWER';
      NO_LOAD_CHECK='Both';
      NO_IO_CHECK='Both';
      NO_ASSERT_CHECK='TRUE';
      NO_DIR_CHECK='TRUE';
      ALLOW_CONNECT='TRUE';
    'GND_M19':
      PIN_NUMBER='(0,0,0,0,0,M19)';
      PINUSE='POWER';
      NO_LOAD_CHECK='Both';
      NO_IO_CHECK='Both';
      NO_ASSERT_CHECK='TRUE';
      NO_DIR_CHECK='TRUE';
      ALLOW_CONNECT='TRUE';
    'GND_N2':
      PIN_NUMBER='(0,0,0,0,0,N2)';
      PINUSE='POWER';
      NO_LOAD_CHECK='Both';
      NO_IO_CHECK='Both';
      NO_ASSERT_CHECK='TRUE';
      NO_DIR_CHECK='TRUE';
      ALLOW_CONNECT='TRUE';
    'GND_N6':
      PIN_NUMBER='(0,0,0,0,0,N6)';
      PINUSE='POWER';
      NO_LOAD_CHECK='Both';
      NO_IO_CHECK='Both';
      NO_ASSERT_CHECK='TRUE';
      NO_DIR_CHECK='TRUE';
      ALLOW_CONNECT='TRUE';
    'GND_N9':
      PIN_NUMBER='(0,0,0,0,0,N9)';
      PINUSE='POWER';
      NO_LOAD_CHECK='Both';
      NO_IO_CHECK='Both';
      NO_ASSERT_CHECK='TRUE';
      NO_DIR_CHECK='TRUE';
      ALLOW_CONNECT='TRUE';
    'GND_N10':
      PIN_NUMBER='(0,0,0,0,0,N10)';
      PINUSE='POWER';
      NO_LOAD_CHECK='Both';
      NO_IO_CHECK='Both';
      NO_ASSERT_CHECK='TRUE';
      NO_DIR_CHECK='TRUE';
      ALLOW_CONNECT='TRUE';
    'GND_N15':
      PIN_NUMBER='(0,0,0,0,0,N15)';
      PINUSE='POWER';
      NO_LOAD_CHECK='Both';
      NO_IO_CHECK='Both';
      NO_ASSERT_CHECK='TRUE';
      NO_DIR_CHECK='TRUE';
      ALLOW_CONNECT='TRUE';
    'GND_N16':
      PIN_NUMBER='(0,0,0,0,0,N16)';
      PINUSE='POWER';
      NO_LOAD_CHECK='Both';
      NO_IO_CHECK='Both';
      NO_ASSERT_CHECK='TRUE';
      NO_DIR_CHECK='TRUE';
      ALLOW_CONNECT='TRUE';
    'GND_N17':
      PIN_NUMBER='(0,0,0,0,0,N17)';
      PINUSE='POWER';
      NO_LOAD_CHECK='Both';
      NO_IO_CHECK='Both';
      NO_ASSERT_CHECK='TRUE';
      NO_DIR_CHECK='TRUE';
      ALLOW_CONNECT='TRUE';
    'GND_N18':
      PIN_NUMBER='(0,0,0,0,0,N18)';
      PINUSE='POWER';
      NO_LOAD_CHECK='Both';
      NO_IO_CHECK='Both';
      NO_ASSERT_CHECK='TRUE';
      NO_DIR_CHECK='TRUE';
      ALLOW_CONNECT='TRUE';
    'GND_N19':
      PIN_NUMBER='(0,0,0,0,0,N19)';
      PINUSE='POWER';
      NO_LOAD_CHECK='Both';
      NO_IO_CHECK='Both';
      NO_ASSERT_CHECK='TRUE';
      NO_DIR_CHECK='TRUE';
      ALLOW_CONNECT='TRUE';
    'GND_AA10':
      PIN_NUMBER='(0,0,0,0,0,AA10)';
      PINUSE='POWER';
      NO_LOAD_CHECK='Both';
      NO_IO_CHECK='Both';
      NO_ASSERT_CHECK='TRUE';
      NO_DIR_CHECK='TRUE';
      ALLOW_CONNECT='TRUE';
    'GND_AA14':
      PIN_NUMBER='(0,0,0,0,0,AA14)';
      PINUSE='POWER';
      NO_LOAD_CHECK='Both';
      NO_IO_CHECK='Both';
      NO_ASSERT_CHECK='TRUE';
      NO_DIR_CHECK='TRUE';
      ALLOW_CONNECT='TRUE';
    'GND_AA15':
      PIN_NUMBER='(0,0,0,0,0,AA15)';
      PINUSE='POWER';
      NO_LOAD_CHECK='Both';
      NO_IO_CHECK='Both';
      NO_ASSERT_CHECK='TRUE';
      NO_DIR_CHECK='TRUE';
      ALLOW_CONNECT='TRUE';
    'GND_AA19':
      PIN_NUMBER='(0,0,0,0,0,AA19)';
      PINUSE='POWER';
      NO_LOAD_CHECK='Both';
      NO_IO_CHECK='Both';
      NO_ASSERT_CHECK='TRUE';
      NO_DIR_CHECK='TRUE';
      ALLOW_CONNECT='TRUE';
    'GND_AA22':
      PIN_NUMBER='(0,0,0,0,0,AA22)';
      PINUSE='POWER';
      NO_LOAD_CHECK='Both';
      NO_IO_CHECK='Both';
      NO_ASSERT_CHECK='TRUE';
      NO_DIR_CHECK='TRUE';
      ALLOW_CONNECT='TRUE';
    'GND_AC2':
      PIN_NUMBER='(0,0,0,0,0,AC2)';
      PINUSE='POWER';
      NO_LOAD_CHECK='Both';
      NO_IO_CHECK='Both';
      NO_ASSERT_CHECK='TRUE';
      NO_DIR_CHECK='TRUE';
      ALLOW_CONNECT='TRUE';
    'GND_AC6':
      PIN_NUMBER='(0,0,0,0,0,AC6)';
      PINUSE='POWER';
      NO_LOAD_CHECK='Both';
      NO_IO_CHECK='Both';
      NO_ASSERT_CHECK='TRUE';
      NO_DIR_CHECK='TRUE';
      ALLOW_CONNECT='TRUE';
    'GND_AC25':
      PIN_NUMBER='(0,0,0,0,0,AC25)';
      PINUSE='POWER';
      NO_LOAD_CHECK='Both';
      NO_IO_CHECK='Both';
      NO_ASSERT_CHECK='TRUE';
      NO_DIR_CHECK='TRUE';
      ALLOW_CONNECT='TRUE';
    'GND_AD1':
      PIN_NUMBER='(0,0,0,0,0,AD1)';
      PINUSE='POWER';
      NO_LOAD_CHECK='Both';
      NO_IO_CHECK='Both';
      NO_ASSERT_CHECK='TRUE';
      NO_DIR_CHECK='TRUE';
      ALLOW_CONNECT='TRUE';
    'GND_AD4':
      PIN_NUMBER='(0,0,0,0,0,AD4)';
      PINUSE='POWER';
      NO_LOAD_CHECK='Both';
      NO_IO_CHECK='Both';
      NO_ASSERT_CHECK='TRUE';
      NO_DIR_CHECK='TRUE';
      ALLOW_CONNECT='TRUE';
    'GND_AE3':
      PIN_NUMBER='(0,0,0,0,0,AE3)';
      PINUSE='POWER';
      NO_LOAD_CHECK='Both';
      NO_IO_CHECK='Both';
      NO_ASSERT_CHECK='TRUE';
      NO_DIR_CHECK='TRUE';
      ALLOW_CONNECT='TRUE';
    'GND_AE6':
      PIN_NUMBER='(0,0,0,0,0,AE6)';
      PINUSE='POWER';
      NO_LOAD_CHECK='Both';
      NO_IO_CHECK='Both';
      NO_ASSERT_CHECK='TRUE';
      NO_DIR_CHECK='TRUE';
      ALLOW_CONNECT='TRUE';
    'GND_AE9':
      PIN_NUMBER='(0,0,0,0,0,AE9)';
      PINUSE='POWER';
      NO_LOAD_CHECK='Both';
      NO_IO_CHECK='Both';
      NO_ASSERT_CHECK='TRUE';
      NO_DIR_CHECK='TRUE';
      ALLOW_CONNECT='TRUE';
    'GND_AE13':
      PIN_NUMBER='(0,0,0,0,0,AE13)';
      PINUSE='POWER';
      NO_LOAD_CHECK='Both';
      NO_IO_CHECK='Both';
      NO_ASSERT_CHECK='TRUE';
      NO_DIR_CHECK='TRUE';
      ALLOW_CONNECT='TRUE';
    'GND_AE17':
      PIN_NUMBER='(0,0,0,0,0,AE17)';
      PINUSE='POWER';
      NO_LOAD_CHECK='Both';
      NO_IO_CHECK='Both';
      NO_ASSERT_CHECK='TRUE';
      NO_DIR_CHECK='TRUE';
      ALLOW_CONNECT='TRUE';
    'GND_AE20':
      PIN_NUMBER='(0,0,0,0,0,AE20)';
      PINUSE='POWER';
      NO_LOAD_CHECK='Both';
      NO_IO_CHECK='Both';
      NO_ASSERT_CHECK='TRUE';
      NO_DIR_CHECK='TRUE';
      ALLOW_CONNECT='TRUE';
    'GND_AE23':
      PIN_NUMBER='(0,0,0,0,0,AE23)';
      PINUSE='POWER';
      NO_LOAD_CHECK='Both';
      NO_IO_CHECK='Both';
      NO_ASSERT_CHECK='TRUE';
      NO_DIR_CHECK='TRUE';
      ALLOW_CONNECT='TRUE';
    'GND_AF1':
      PIN_NUMBER='(0,0,0,0,0,AF1)';
      PINUSE='POWER';
      NO_LOAD_CHECK='Both';
      NO_IO_CHECK='Both';
      NO_ASSERT_CHECK='TRUE';
      NO_DIR_CHECK='TRUE';
      ALLOW_CONNECT='TRUE';
    'GND_AF4':
      PIN_NUMBER='(0,0,0,0,0,AF4)';
      PINUSE='POWER';
      NO_LOAD_CHECK='Both';
      NO_IO_CHECK='Both';
      NO_ASSERT_CHECK='TRUE';
      NO_DIR_CHECK='TRUE';
      ALLOW_CONNECT='TRUE';
    'GND_AF26':
      PIN_NUMBER='(0,0,0,0,0,AF26)';
      PINUSE='POWER';
      NO_LOAD_CHECK='Both';
      NO_IO_CHECK='Both';
      NO_ASSERT_CHECK='TRUE';
      NO_DIR_CHECK='TRUE';
      ALLOW_CONNECT='TRUE';
    'GND_P4':
      PIN_NUMBER='(0,0,0,0,0,P4)';
      PINUSE='POWER';
      NO_LOAD_CHECK='Both';
      NO_IO_CHECK='Both';
      NO_ASSERT_CHECK='TRUE';
      NO_DIR_CHECK='TRUE';
      ALLOW_CONNECT='TRUE';
    'GND_P9':
      PIN_NUMBER='(0,0,0,0,0,P9)';
      PINUSE='POWER';
      NO_LOAD_CHECK='Both';
      NO_IO_CHECK='Both';
      NO_ASSERT_CHECK='TRUE';
      NO_DIR_CHECK='TRUE';
      ALLOW_CONNECT='TRUE';
    'GND_P10':
      PIN_NUMBER='(0,0,0,0,0,P10)';
      PINUSE='POWER';
      NO_LOAD_CHECK='Both';
      NO_IO_CHECK='Both';
      NO_ASSERT_CHECK='TRUE';
      NO_DIR_CHECK='TRUE';
      ALLOW_CONNECT='TRUE';
    'GND_P15':
      PIN_NUMBER='(0,0,0,0,0,P15)';
      PINUSE='POWER';
      NO_LOAD_CHECK='Both';
      NO_IO_CHECK='Both';
      NO_ASSERT_CHECK='TRUE';
      NO_DIR_CHECK='TRUE';
      ALLOW_CONNECT='TRUE';
    'GND_P16':
      PIN_NUMBER='(0,0,0,0,0,P16)';
      PINUSE='POWER';
      NO_LOAD_CHECK='Both';
      NO_IO_CHECK='Both';
      NO_ASSERT_CHECK='TRUE';
      NO_DIR_CHECK='TRUE';
      ALLOW_CONNECT='TRUE';
    'GND_P17':
      PIN_NUMBER='(0,0,0,0,0,P17)';
      PINUSE='POWER';
      NO_LOAD_CHECK='Both';
      NO_IO_CHECK='Both';
      NO_ASSERT_CHECK='TRUE';
      NO_DIR_CHECK='TRUE';
      ALLOW_CONNECT='TRUE';
    'GND_P18':
      PIN_NUMBER='(0,0,0,0,0,P18)';
      PINUSE='POWER';
      NO_LOAD_CHECK='Both';
      NO_IO_CHECK='Both';
      NO_ASSERT_CHECK='TRUE';
      NO_DIR_CHECK='TRUE';
      ALLOW_CONNECT='TRUE';
    'GND_P19':
      PIN_NUMBER='(0,0,0,0,0,P19)';
      PINUSE='POWER';
      NO_LOAD_CHECK='Both';
      NO_IO_CHECK='Both';
      NO_ASSERT_CHECK='TRUE';
      NO_DIR_CHECK='TRUE';
      ALLOW_CONNECT='TRUE';
    'GND_AA20':
      PIN_NUMBER='(0,0,0,0,0,AA20)';
      PINUSE='POWER';
      NO_LOAD_CHECK='Both';
      NO_IO_CHECK='Both';
      NO_ASSERT_CHECK='TRUE';
      NO_DIR_CHECK='TRUE';
      ALLOW_CONNECT='TRUE';
    'GND_U23':
      PIN_NUMBER='(0,0,0,0,0,U23)';
      PINUSE='POWER';
      NO_LOAD_CHECK='Both';
      NO_IO_CHECK='Both';
      NO_ASSERT_CHECK='TRUE';
      NO_DIR_CHECK='TRUE';
      ALLOW_CONNECT='TRUE';
  end_pin;
  body
      PART_NAME='AST2600A3GP';
      BODY_NAME='AST2600A3GP';
      PHYS_DES_PREFIX='U';
      CLASS='IC';
      STANDARD='';
      LIFECYCLE='';
      JEDEC_TYPE='BGA624_0-8_21X21XA';
      DESCRIPTION='IC(624P)AST2600A3-GP(TFBGA)';
      MANUFTR='APD';
      MANUF_PN='AST2600A3-GP';
      RD_CMPLS_LVL='EP(V1)';
      CMPLS_LVL='';
      FROM_PJ='A5G-JASMINE';
      DIP_SMD='';
      DATA='APD_AST2600A3-GP.pdf';
      EE_CHECK_LIST='';
      FP_ECN='';
      PSL='';
      CREATOR='';
      STATUS='';
      MSD='';
      ESD_CDM='';
      ESD_HBM='';
      ESD_MM='';
      PIN_LENGTH_SHORT_PIN='0 MILS';
      PIN_LENGTH_LONG_PIN='0 MILS';
      CREATEDAY='20210709';
      PARENT_PART_TYPE='AST2600A3GP';
      PARENT_PPT='AST2600A3GP';
      PARENT_PPT_PART='AST2600A3GP-AST2600A3-GP,SMLF,IC,AJ026000T06';
  end_body;
end_primitive;
primitive 'BAS70057F-BAS70-05-7-F,SMLF,ICA';
  pin
    'A':
      PIN_NUMBER='(2)';
      INPUT_LOAD='(-0.01,0.01)';
      PINUSE='IN';
    'B':
      PIN_NUMBER='(1)';
      INPUT_LOAD='(-0.01,0.01)';
      PINUSE='IN';
    'C':
      PIN_NUMBER='(3)';
      BIDIRECTIONAL='TRUE';
      INPUT_LOAD='(-0.01,0.01)';
      OUTPUT_LOAD='(1.0,-1.0)';
      PINUSE='BI';
  end_pin;
  body
      PART_NAME='BAS70057F';
      BODY_NAME='BAS70057F';
      PHYS_DES_PREFIX='U';
      CLASS='IC';
      STANDARD='End of Design';
      LIFECYCLE='Comp-Approve';
      JEDEC_TYPE='SOT23_123XB';
      DESCRIPTION='DIODE SMD BAS70-05-7-F(70V,SHTKY,SOT-23)';
      MANUFTR='DDS';
      MANUF_PN='BAS70-05-7-F';
      RD_CMPLS_LVL='EP(V1)';
      CMPLS_LVL='EP(V1)';
      DIP_SMD='';
      FP_ECN='';
      FROM_PJ='S1D-OZ';
      DATA='DDS_BAS70-04-05-06.pdf';
      EE_CHECK_LIST='';
      STATUS='';
      PSL='';
      PREFERENCE='';
      CREATOR='';
      CREATEDAY='20121220';
      PARENT_PART_TYPE='BAS70057F';
      PARENT_PPT='BAS70057F';
      PARENT_PPT_PART='BAS70057F-BAS70-05-7-F,SMLF,IC,BC0BAS70Z01';
  end_body;
end_primitive;
primitive 'BAT54C-BAT54C,SMLF,IC,BCBAT54CA';
  pin
    'A':
      PIN_NUMBER='(2)';
      INPUT_LOAD='(-0.01,0.01)';
      PINUSE='IN';
    'B':
      PIN_NUMBER='(1)';
      INPUT_LOAD='(-0.01,0.01)';
      PINUSE='IN';
    'C':
      PIN_NUMBER='(3)';
      INPUT_LOAD='(-0.01,0.01)';
      OUTPUT_LOAD='(1.0,-1.0)';
      BIDIRECTIONAL='TRUE';
      PINUSE='BI';
  end_pin;
  body
      CLASS='IC';
      PART_NAME='BAT54C';
      PHYS_DES_PREFIX='U';
      JEDEC_TYPE='SOT23_123';
      DESCRIPTION='DIODE SMD BAT54C(30V,0.2A,SCHOTTKY)';
      MANUFTR='PJT';
      MANUF_PN='BAT54C';
      RD_CMPLS_LVL='EP(V1)';
      CMPLS_LVL='EP(V1)';
      DIP_SMD='';
      FP_ECN='';
      FROM_PJ='TU1D-MICHAEL';
      DATA='BAT54_series.pdf';
      EE_CHECK_LIST='';
      STANDARD='End of Design';
      PSL='';
      PREFERENCE='';
      LIFECYCLE='Comp-Approve';
      CREATOR='';
      CREATEDAY='20111020';
      STATUS='';
      PARENT_PART_TYPE='BAT54C';
      PARENT_PPT='BAT54C';
      PARENT_PPT_PART='BAT54C-BAT54C,SMLF,IC,BCBAT54CZ04';
  end_body;
end_primitive;
primitive 'BZA462A-BZA462A,SMLF,EMPTY,BCZA';
  pin
    '2':
      PIN_NUMBER='(2)';
      BIDIRECTIONAL='TRUE';
      INPUT_LOAD='(-0.01,0.01)';
      OUTPUT_LOAD='(1.0,-1.0)';
      PINUSE='BI';
    '5':
      PIN_NUMBER='(5)';
      BIDIRECTIONAL='TRUE';
      INPUT_LOAD='(-0.01,0.01)';
      OUTPUT_LOAD='(1.0,-1.0)';
      PINUSE='BI';
    '1':
      PIN_NUMBER='(1)';
      BIDIRECTIONAL='TRUE';
      INPUT_LOAD='(-0.01,0.01)';
      OUTPUT_LOAD='(1.0,-1.0)';
      PINUSE='BI';
    '3':
      PIN_NUMBER='(3)';
      BIDIRECTIONAL='TRUE';
      INPUT_LOAD='(-0.01,0.01)';
      OUTPUT_LOAD='(1.0,-1.0)';
      PINUSE='BI';
    '4':
      PIN_NUMBER='(4)';
      BIDIRECTIONAL='TRUE';
      INPUT_LOAD='(-0.01,0.01)';
      OUTPUT_LOAD='(1.0,-1.0)';
      PINUSE='BI';
    '6':
      PIN_NUMBER='(6)';
      BIDIRECTIONAL='TRUE';
      INPUT_LOAD='(-0.01,0.01)';
      OUTPUT_LOAD='(1.0,-1.0)';
      PINUSE='BI';
  end_pin;
  body
      PART_NAME='BZA462A';
      BODY_NAME='BZA462A';
      PHYS_DES_PREFIX='D';
      CLASS='IC';
      STANDARD='';
      LIFECYCLE='';
      JEDEC_TYPE='SOT457XA';
      DESCRIPTION='DIODE SMD BZA462A(6.2V,100MA,SOT457)';
      MANUFTR='PHI';
      MANUF_PN='BZA462A';
      RD_CMPLS_LVL='EP';
      CMPLS_LVL='EP';
      DIP_SMD='';
      FP_ECN='';
      FROM_PJ='S56-PARK';
      DATA='PHI_BZA462A.pdf';
      EE_CHECK_LIST='';
      STATUS='';
      PSL='';
      PREFERENCE='';
      CREATOR='';
      CREATEDAY='20100429';
      ESD_CDM='';
      ESD_HBM='';
      ESD_MM='';
      MSD='';
      PIN_LENGTH_LONG_PIN='';
      PIN_LENGTH_SHORT_PIN='';
      PARENT_PART_TYPE='BZA462A';
      PARENT_PPT='BZA462A';
      PARENT_PPT_PART='BZA462A-BZA462A,SMLF,EMPTY,BCZA462AZ01';
  end_body;
end_primitive;
primitive 'CONN8_210HP1080BR1-CONN8_210-HA';
  pin
    '1':
      PIN_NUMBER='(1)';
      BIDIRECTIONAL='TRUE';
      INPUT_LOAD='(-0.01,0.01)';
      OUTPUT_LOAD='(1.0,-1.0)';
      PINUSE='BI';
    '2':
      PIN_NUMBER='(2)';
      BIDIRECTIONAL='TRUE';
      INPUT_LOAD='(-0.01,0.01)';
      OUTPUT_LOAD='(1.0,-1.0)';
      PINUSE='BI';
    '3':
      PIN_NUMBER='(3)';
      BIDIRECTIONAL='TRUE';
      INPUT_LOAD='(-0.01,0.01)';
      OUTPUT_LOAD='(1.0,-1.0)';
      PINUSE='BI';
    '4':
      PIN_NUMBER='(4)';
      BIDIRECTIONAL='TRUE';
      INPUT_LOAD='(-0.01,0.01)';
      OUTPUT_LOAD='(1.0,-1.0)';
      PINUSE='BI';
    '5':
      PIN_NUMBER='(5)';
      BIDIRECTIONAL='TRUE';
      INPUT_LOAD='(-0.01,0.01)';
      OUTPUT_LOAD='(1.0,-1.0)';
      PINUSE='BI';
    '6':
      PIN_NUMBER='(6)';
      BIDIRECTIONAL='TRUE';
      INPUT_LOAD='(-0.01,0.01)';
      OUTPUT_LOAD='(1.0,-1.0)';
      PINUSE='BI';
    '7':
      PIN_NUMBER='(7)';
      BIDIRECTIONAL='TRUE';
      INPUT_LOAD='(-0.01,0.01)';
      OUTPUT_LOAD='(1.0,-1.0)';
      PINUSE='BI';
    '8':
      PIN_NUMBER='(8)';
      BIDIRECTIONAL='TRUE';
      INPUT_LOAD='(-0.01,0.01)';
      OUTPUT_LOAD='(1.0,-1.0)';
      PINUSE='BI';
  end_pin;
  body
      PART_NAME='CONN8_210HP1080BR1';
      BODY_NAME='CONN8_210HP1080BR1';
      PHYS_DES_PREFIX='J';
      CLASS='IO';
      STANDARD='';
      LIFECYCLE='';
      JEDEC_TYPE='HEADER1X8XE';
      DESCRIPTION='CONN DIP HEADER 8P 1R MS(P2.54,H8.6)';
      MANUFTR='PRX';
      MANUF_PN='210-HP1-080BR1';
      RD_CMPLS_LVL='EP(V1)';
      CMPLS_LVL='EP(V1)';
      DIP_SMD='DIP';
      FROM_PJ='F08-SHERRY';
      DATA='PRX_210-HP1-080BR1.pdf';
      FP_ECN='';
      EE_CHECK_LIST='';
      CREATOR='';
      CREATEDAY='20160406';
      PSL='';
      STATUS='';
      ESD_CDM='';
      ESD_HBM='';
      ESD_MM='';
      MSD='';
      PIN_LENGTH_LONG_PIN='119 MILS';
      PIN_LENGTH_SHORT_PIN='119 MILS';
      PARENT_PART_TYPE='CONN8_210HP1080BR1';
      PARENT_PPT='CONN8_210HP1080BR1';
      PARENT_PPT_PART='CONN8_210HP1080BR1-CONN8_210-HP1-080BR1,THLF,IO,DFHD08MS392';
  end_body;
end_primitive;
primitive 'CONN8_TSW10407FD-CONN8_TSW-104A';
  pin
    '5':
      PIN_NUMBER='(5)';
      BIDIRECTIONAL='TRUE';
      INPUT_LOAD='(-0.01,0.01)';
      OUTPUT_LOAD='(1.0,-1.0)';
      PINUSE='BI';
    '6':
      PIN_NUMBER='(6)';
      BIDIRECTIONAL='TRUE';
      INPUT_LOAD='(-0.01,0.01)';
      OUTPUT_LOAD='(1.0,-1.0)';
      PINUSE='BI';
    '7':
      PIN_NUMBER='(7)';
      BIDIRECTIONAL='TRUE';
      INPUT_LOAD='(-0.01,0.01)';
      OUTPUT_LOAD='(1.0,-1.0)';
      PINUSE='BI';
    '8':
      PIN_NUMBER='(8)';
      BIDIRECTIONAL='TRUE';
      INPUT_LOAD='(-0.01,0.01)';
      OUTPUT_LOAD='(1.0,-1.0)';
      PINUSE='BI';
    '3':
      PIN_NUMBER='(3)';
      BIDIRECTIONAL='TRUE';
      INPUT_LOAD='(-0.01,0.01)';
      OUTPUT_LOAD='(1.0,-1.0)';
      PINUSE='BI';
    '1':
      PIN_NUMBER='(1)';
      BIDIRECTIONAL='TRUE';
      INPUT_LOAD='(-0.01,0.01)';
      OUTPUT_LOAD='(1.0,-1.0)';
      PINUSE='BI';
    '4':
      PIN_NUMBER='(4)';
      BIDIRECTIONAL='TRUE';
      INPUT_LOAD='(-0.01,0.01)';
      OUTPUT_LOAD='(1.0,-1.0)';
      PINUSE='BI';
    '2':
      PIN_NUMBER='(2)';
      BIDIRECTIONAL='TRUE';
      INPUT_LOAD='(-0.01,0.01)';
      OUTPUT_LOAD='(1.0,-1.0)';
      PINUSE='BI';
  end_pin;
  body
      PART_NAME='CONN8_TSW10407FD';
      BODY_NAME='CONN8_TSW10407FD';
      PHYS_DES_PREFIX='J';
      CLASS='IO';
      STANDARD='';
      LIFECYCLE='';
      JEDEC_TYPE='HEADER2X4XF';
      DESCRIPTION='CONN DIP HEADER 8P 2R MS(P2.54,H8.38)';
      MANUFTR='STC';
      MANUF_PN='TSW-104-07-F-D';
      RD_CMPLS_LVL='EU(V1)';
      CMPLS_LVL='EU(V1)';
      DIP_SMD='DIP';
      FROM_PJ='T2MK-CHIA-LU';
      DATA='STC_TSW-104-07-F-D_REVDN.pdf';
      FP_ECN='TSW-104-07-F-D.msg';
      EE_CHECK_LIST='';
      CREATOR='';
      CREATEDAY='20210514';
      PSL='';
      STATUS='';
      ESD_CDM='';
      ESD_HBM='';
      ESD_MM='';
      MSD='';
      PIN_LENGTH_LONG_PIN='100 MILS';
      PIN_LENGTH_SHORT_PIN='100 MILS';
      PARENT_PART_TYPE='CONN8_TSW10407FD';
      PARENT_PPT='CONN8_TSW10407FD';
      PARENT_PPT_PART='CONN8_TSW10407FD-CONN8_TSW-104-07-F-D,THLF,EMPTY,DFHD08MS225';
  end_body;
end_primitive;
primitive 'CONN9_GSB3111315HR-CONN9_GSB31A';
  pin
    'VBUS':
      PIN_NUMBER='(1)';
      PINUSE='POWER';
      NO_LOAD_CHECK='Both';
      NO_IO_CHECK='Both';
      NO_ASSERT_CHECK='TRUE';
      NO_DIR_CHECK='TRUE';
      ALLOW_CONNECT='TRUE';
    'GND':
      PIN_NUMBER='(4)';
      PINUSE='POWER';
      NO_LOAD_CHECK='Both';
      NO_IO_CHECK='Both';
      NO_ASSERT_CHECK='TRUE';
      NO_DIR_CHECK='TRUE';
      ALLOW_CONNECT='TRUE';
    'G1':
      PIN_NUMBER='(G1)';
      PINUSE='POWER';
      NO_LOAD_CHECK='Both';
      NO_IO_CHECK='Both';
      NO_ASSERT_CHECK='TRUE';
      NO_DIR_CHECK='TRUE';
      ALLOW_CONNECT='TRUE';
    'G2':
      PIN_NUMBER='(G2)';
      PINUSE='POWER';
      NO_LOAD_CHECK='Both';
      NO_IO_CHECK='Both';
      NO_ASSERT_CHECK='TRUE';
      NO_DIR_CHECK='TRUE';
      ALLOW_CONNECT='TRUE';
    'SSTX+':
      PIN_NUMBER='(9)';
      INPUT_LOAD='(-0.01,0.01)';
      PINUSE='IN';
    'SSTX-':
      PIN_NUMBER='(8)';
      INPUT_LOAD='(-0.01,0.01)';
      PINUSE='IN';
    'D-':
      PIN_NUMBER='(2)';
      BIDIRECTIONAL='TRUE';
      INPUT_LOAD='(-0.01,0.01)';
      OUTPUT_LOAD='(1.0,-1.0)';
      PINUSE='BI';
    'D+':
      PIN_NUMBER='(3)';
      BIDIRECTIONAL='TRUE';
      INPUT_LOAD='(-0.01,0.01)';
      OUTPUT_LOAD='(1.0,-1.0)';
      PINUSE='BI';
    'SSRX+':
      PIN_NUMBER='(6)';
      OUTPUT_LOAD='(1.0,-1.0)';
      PINUSE='OUT';
    'GND_D':
      PIN_NUMBER='(7)';
      PINUSE='POWER';
      NO_LOAD_CHECK='Both';
      NO_IO_CHECK='Both';
      NO_ASSERT_CHECK='TRUE';
      NO_DIR_CHECK='TRUE';
      ALLOW_CONNECT='TRUE';
    'SSRX-':
      PIN_NUMBER='(5)';
      OUTPUT_LOAD='(1.0,-1.0)';
      PINUSE='OUT';
  end_pin;
  body
      PART_NAME='CONN9_GSB3111315HR';
      BODY_NAME='CONN9_GSB3111315HR';
      PHYS_DES_PREFIX='J';
      CLASS='IO';
      STANDARD='';
      LIFECYCLE='';
      JEDEC_TYPE='USB1XBH';
      DESCRIPTION='CONN DIP USB3.0 9P 2R FR(P2.0,H7.74)';
      MANUFTR='APL';
      MANUF_PN='GSB3111315HR';
      RD_CMPLS_LVL='EP(V1)';
      CMPLS_LVL='EP(V1)';
      DIP_SMD='DIP';
      FROM_PJ='S5B-YU-LIN';
      DATA='APL_GSB3111315HR.pdf';
      FP_ECN='';
      EE_CHECK_LIST='';
      CREATOR='';
      CREATEDAY='20220819';
      PSL='';
      STATUS='';
      ESD_CDM='';
      ESD_HBM='';
      ESD_MM='';
      MSD='';
      PIN_LENGTH_LONG_PIN='136 MILS';
      PIN_LENGTH_SHORT_PIN='105 MILS';
      PARENT_PART_TYPE='CONN9_GSB3111315HR';
      PARENT_PPT='CONN9_GSB3111315HR';
      PARENT_PPT_PART='CONN9_GSB3111315HR-CONN9_GSB3111315HR,THLF,IO,DFHS09FR401';
  end_body;
end_primitive;
primitive 'DIODE_BIDIRECTIONAL-UCLAMP0511A';
  pin
    'A':
      PIN_NUMBER='(A)';
      BIDIRECTIONAL='TRUE';
      INPUT_LOAD='(-0.01,0.01)';
      OUTPUT_LOAD='(1.0,-1.0)';
      PINUSE='BI';
    'C':
      PIN_NUMBER='(C)';
      BIDIRECTIONAL='TRUE';
      INPUT_LOAD='(-0.01,0.01)';
      OUTPUT_LOAD='(1.0,-1.0)';
      PINUSE='BI';
  end_pin;
  body
      PART_NAME='DIODE_BIDIRECTIONAL';
      BODY_NAME='DIODE_BIDIRECTIONAL';
      PHYS_DES_PREFIX='D';
      CLASS='IC';
      STANDARD='';
      LIFECYCLE='';
      JEDEC_TYPE='SLP1006P2T';
      DESCRIPTION='DIODE SMD TVS UCLAMP0511T(5V,SLP1006P2T)';
      MANUFTR='STH';
      MANUF_PN='UCLAMP0511T.TCT';
      RD_CMPLS_LVL='EP(V1)';
      CMPLS_LVL='';
      DIP_SMD='';
      FP_ECN='';
      FROM_PJ='JBR-CHIH-FENG';
      DATA='STH_uClamp0511T.pdf';
      EE_CHECK_LIST='';
      STATUS='';
      PSL='';
      PREFERENCE='';
      CREATOR='';
      CREATEDAY='20130323';
      ESD_CDM='';
      ESD_HBM='';
      ESD_MM='';
      MSD='';
      PIN_LENGTH_LONG_PIN='';
      PIN_LENGTH_SHORT_PIN='';
      PARENT_PART_TYPE='DIODE_BIDIRECTIONAL';
      PARENT_PPT='DIODE_BIDIRECTIONAL';
      PARENT_PPT_PART='DIODE_BIDIRECTIONAL-UCLAMP0511T,SMLF,IC,BC00511TZ00';
  end_body;
end_primitive;
primitive 'DT1240E04LP7-DT1240E-04LP-7,SMA';
  pin
    'IO1':
      PIN_NUMBER='(1)';
      BIDIRECTIONAL='TRUE';
      INPUT_LOAD='(-0.01,0.01)';
      OUTPUT_LOAD='(1.0,-1.0)';
      PINUSE='BI';
    'VSS1':
      PIN_NUMBER='(3)';
      PINUSE='POWER';
      NO_LOAD_CHECK='Both';
      NO_IO_CHECK='Both';
      NO_ASSERT_CHECK='TRUE';
      NO_DIR_CHECK='TRUE';
      ALLOW_CONNECT='TRUE';
    'IO3':
      PIN_NUMBER='(4)';
      BIDIRECTIONAL='TRUE';
      INPUT_LOAD='(-0.01,0.01)';
      OUTPUT_LOAD='(1.0,-1.0)';
      PINUSE='BI';
    'NC1':
      PIN_NUMBER='(6)';
      OUTPUT_TYPE='(TS,TS)';
      INPUT_LOAD='(-0.01,0.01)';
      OUTPUT_LOAD='(1.0,-1.0)';
      PINUSE='TRI';
    'VSS2':
      PIN_NUMBER='(8)';
      PINUSE='POWER';
      NO_LOAD_CHECK='Both';
      NO_IO_CHECK='Both';
      NO_ASSERT_CHECK='TRUE';
      NO_DIR_CHECK='TRUE';
      ALLOW_CONNECT='TRUE';
    'NC3':
      PIN_NUMBER='(9)';
      OUTPUT_TYPE='(TS,TS)';
      INPUT_LOAD='(-0.01,0.01)';
      OUTPUT_LOAD='(1.0,-1.0)';
      PINUSE='TRI';
    'NC4':
      PIN_NUMBER='(10)';
      OUTPUT_TYPE='(TS,TS)';
      INPUT_LOAD='(-0.01,0.01)';
      OUTPUT_LOAD='(1.0,-1.0)';
      PINUSE='TRI';
    'IO2':
      PIN_NUMBER='(2)';
      BIDIRECTIONAL='TRUE';
      INPUT_LOAD='(-0.01,0.01)';
      OUTPUT_LOAD='(1.0,-1.0)';
      PINUSE='BI';
    'IO4':
      PIN_NUMBER='(5)';
      BIDIRECTIONAL='TRUE';
      INPUT_LOAD='(-0.01,0.01)';
      OUTPUT_LOAD='(1.0,-1.0)';
      PINUSE='BI';
    'NC2':
      PIN_NUMBER='(7)';
      OUTPUT_TYPE='(TS,TS)';
      INPUT_LOAD='(-0.01,0.01)';
      OUTPUT_LOAD='(1.0,-1.0)';
      PINUSE='TRI';
  end_pin;
  body
      PART_NAME='DT1240E04LP7';
      BODY_NAME='DT1240E04LP7';
      PHYS_DES_PREFIX='D';
      CLASS='IC';
      STANDARD='';
      LIFECYCLE='';
      JEDEC_TYPE='U-DFN2510-10_0-5_2-5X1';
      DESCRIPTION='DIODE ARRAY DT1240E-04LP-7 (3.3V)';
      MANUFTR='DDS';
      MANUF_PN='DT1240E-04LP-7';
      RD_CMPLS_LVL='EP(V1)';
      CMPLS_LVL='EP(V1)';
      DIP_SMD='';
      FP_ECN='';
      FROM_PJ='F0CE-GARY';
      DATA='DDS_DT1240E-04LP-7.pdf';
      EE_CHECK_LIST='';
      STATUS='';
      PSL='';
      PREFERENCE='';
      CREATOR='';
      CREATEDAY='20210611';
      ESD_CDM='';
      ESD_HBM='';
      ESD_MM='';
      MSD='';
      PIN_LENGTH_LONG_PIN='0 MILS';
      PIN_LENGTH_SHORT_PIN='0 MILS';
      PARENT_PART_TYPE='DT1240E04LP7';
      PARENT_PPT='DT1240E04LP7';
      PARENT_PPT_PART='DT1240E04LP7-DT1240E-04LP-7,SMLF,IC,BC001240Z01';
  end_body;
end_primitive;
primitive 'DUMMY_SYMBOL-BIOS_FLASH,MECH,MA';
  pin
    '1':
      PIN_NUMBER='(1)';
      OUTPUT_TYPE='(TS,TS)';
      INPUT_LOAD='(-0.01,0.01)';
      OUTPUT_LOAD='(1.0,-1.0)';
      PINUSE='TRI';
  end_pin;
  body
      PART_NAME='DUMMY_SYMBOL';
      BODY_NAME='DUMMY_SYMBOL';
      PHYS_DES_PREFIX='DM';
      CLASS='IO';
      STANDARD='';
      LIFECYCLE='';
      JEDEC_TYPE='TP30_FOR_BOM';
      DESCRIPTION='BIOS_FLASH';
      MANUFTR='';
      MANUF_PN='';
      RD_CMPLS_LVL='';
      CMPLS_LVL='';
      DIP_SMD='';
      FROM_PJ='';
      DATA='';
      FP_ECN='';
      EE_CHECK_LIST='';
      PSL='';
      PREFERENCE='';
      CREATOR='';
      CREATEDAY='20141104';
      STATUS='';
      PARENT_PART_TYPE='DUMMY_SYMBOL';
      PARENT_PPT='DUMMY_SYMBOL';
      PARENT_PPT_PART='DUMMY_SYMBOL-BIOS_FLASH,MECH,MECH,DUMMY9';
  end_body;
end_primitive;
primitive 'DUMMY_SYMBOL-BMC_FLASH,MECH,EMA';
  pin
    '1':
      PIN_NUMBER='(1)';
      OUTPUT_TYPE='(TS,TS)';
      INPUT_LOAD='(-0.01,0.01)';
      OUTPUT_LOAD='(1.0,-1.0)';
      PINUSE='TRI';
  end_pin;
  body
      PART_NAME='DUMMY_SYMBOL';
      BODY_NAME='DUMMY_SYMBOL';
      PHYS_DES_PREFIX='DM';
      CLASS='IO';
      STANDARD='';
      LIFECYCLE='';
      JEDEC_TYPE='TP30_FOR_BOM';
      DESCRIPTION='BMC_FLASH';
      MANUFTR='';
      MANUF_PN='';
      RD_CMPLS_LVL='';
      CMPLS_LVL='';
      DIP_SMD='';
      FROM_PJ='';
      DATA='';
      FP_ECN='';
      EE_CHECK_LIST='';
      PSL='';
      PREFERENCE='';
      CREATOR='';
      CREATEDAY='20141104';
      STATUS='';
      PARENT_PART_TYPE='DUMMY_SYMBOL';
      PARENT_PPT='DUMMY_SYMBOL';
      PARENT_PPT_PART='DUMMY_SYMBOL-BMC_FLASH,MECH,EMPTY,DUMMY8';
  end_body;
end_primitive;
primitive 'FCONN168_ME1016810202011_SCM-FA';
  pin
    'P12V_AUX_OA1':
      PIN_NUMBER='(OA1)';
      PINUSE='POWER';
      NO_LOAD_CHECK='Both';
      NO_IO_CHECK='Both';
      NO_ASSERT_CHECK='TRUE';
      NO_DIR_CHECK='TRUE';
      ALLOW_CONNECT='TRUE';
    'P12V_AUX_OA2':
      PIN_NUMBER='(OA2)';
      PINUSE='POWER';
      NO_LOAD_CHECK='Both';
      NO_IO_CHECK='Both';
      NO_ASSERT_CHECK='TRUE';
      NO_DIR_CHECK='TRUE';
      ALLOW_CONNECT='TRUE';
    'GND_OA3':
      PIN_NUMBER='(OA3)';
      PINUSE='POWER';
      NO_LOAD_CHECK='Both';
      NO_IO_CHECK='Both';
      NO_ASSERT_CHECK='TRUE';
      NO_DIR_CHECK='TRUE';
      ALLOW_CONNECT='TRUE';
    'GND_OA4':
      PIN_NUMBER='(OA4)';
      PINUSE='POWER';
      NO_LOAD_CHECK='Both';
      NO_IO_CHECK='Both';
      NO_ASSERT_CHECK='TRUE';
      NO_DIR_CHECK='TRUE';
      ALLOW_CONNECT='TRUE';
    'I3C_0_SCL':
      PIN_NUMBER='(OA5)';
      BIDIRECTIONAL='TRUE';
      INPUT_LOAD='(-0.01,0.01)';
      OUTPUT_LOAD='(1.0,-1.0)';
      PINUSE='BI';
    'I3C_0_SDA':
      PIN_NUMBER='(OA6)';
      BIDIRECTIONAL='TRUE';
      INPUT_LOAD='(-0.01,0.01)';
      OUTPUT_LOAD='(1.0,-1.0)';
      PINUSE='BI';
    'I3C_1_SCL':
      PIN_NUMBER='(OA7)';
      BIDIRECTIONAL='TRUE';
      INPUT_LOAD='(-0.01,0.01)';
      OUTPUT_LOAD='(1.0,-1.0)';
      PINUSE='BI';
    'I3C_1_SDA':
      PIN_NUMBER='(OA8)';
      BIDIRECTIONAL='TRUE';
      INPUT_LOAD='(-0.01,0.01)';
      OUTPUT_LOAD='(1.0,-1.0)';
      PINUSE='BI';
    'I3C_2_SCL':
      PIN_NUMBER='(OA9)';
      BIDIRECTIONAL='TRUE';
      INPUT_LOAD='(-0.01,0.01)';
      OUTPUT_LOAD='(1.0,-1.0)';
      PINUSE='BI';
    'I3C_2_SDA':
      PIN_NUMBER='(OA10)';
      BIDIRECTIONAL='TRUE';
      INPUT_LOAD='(-0.01,0.01)';
      OUTPUT_LOAD='(1.0,-1.0)';
      PINUSE='BI';
    'I3C_3_SCL':
      PIN_NUMBER='(OA11)';
      BIDIRECTIONAL='TRUE';
      INPUT_LOAD='(-0.01,0.01)';
      OUTPUT_LOAD='(1.0,-1.0)';
      PINUSE='BI';
    'I3C_3_SDA':
      PIN_NUMBER='(OA12)';
      BIDIRECTIONAL='TRUE';
      INPUT_LOAD='(-0.01,0.01)';
      OUTPUT_LOAD='(1.0,-1.0)';
      PINUSE='BI';
    'GND_OA13':
      PIN_NUMBER='(OA13)';
      PINUSE='POWER';
      NO_LOAD_CHECK='Both';
      NO_IO_CHECK='Both';
      NO_ASSERT_CHECK='TRUE';
      NO_DIR_CHECK='TRUE';
      ALLOW_CONNECT='TRUE';
    'VIRTUAL_RESEAT':
      PIN_NUMBER='(OA14)';
      BIDIRECTIONAL='TRUE';
      INPUT_LOAD='(-0.01,0.01)';
      OUTPUT_LOAD='(1.0,-1.0)';
      PINUSE='BI';
    'I2C_0_SCL':
      PIN_NUMBER='(A1)';
      BIDIRECTIONAL='TRUE';
      INPUT_LOAD='(-0.01,0.01)';
      OUTPUT_LOAD='(1.0,-1.0)';
      PINUSE='BI';
    'I2C_0_SDA':
      PIN_NUMBER='(A2)';
      BIDIRECTIONAL='TRUE';
      INPUT_LOAD='(-0.01,0.01)';
      OUTPUT_LOAD='(1.0,-1.0)';
      PINUSE='BI';
    'I2C_1_SCL':
      PIN_NUMBER='(A3)';
      BIDIRECTIONAL='TRUE';
      INPUT_LOAD='(-0.01,0.01)';
      OUTPUT_LOAD='(1.0,-1.0)';
      PINUSE='BI';
    'I2C_1_SDA':
      PIN_NUMBER='(A4)';
      BIDIRECTIONAL='TRUE';
      INPUT_LOAD='(-0.01,0.01)';
      OUTPUT_LOAD='(1.0,-1.0)';
      PINUSE='BI';
    'I2C_2_SCL':
      PIN_NUMBER='(A5)';
      BIDIRECTIONAL='TRUE';
      INPUT_LOAD='(-0.01,0.01)';
      OUTPUT_LOAD='(1.0,-1.0)';
      PINUSE='BI';
    'I2C_2_SDA':
      PIN_NUMBER='(A6)';
      BIDIRECTIONAL='TRUE';
      INPUT_LOAD='(-0.01,0.01)';
      OUTPUT_LOAD='(1.0,-1.0)';
      PINUSE='BI';
    'I2C_3_SCL':
      PIN_NUMBER='(A7)';
      BIDIRECTIONAL='TRUE';
      INPUT_LOAD='(-0.01,0.01)';
      OUTPUT_LOAD='(1.0,-1.0)';
      PINUSE='BI';
    'I2C_3_SDA':
      PIN_NUMBER='(A8)';
      BIDIRECTIONAL='TRUE';
      INPUT_LOAD='(-0.01,0.01)';
      OUTPUT_LOAD='(1.0,-1.0)';
      PINUSE='BI';
    'I2C_4_SCL':
      PIN_NUMBER='(A9)';
      BIDIRECTIONAL='TRUE';
      INPUT_LOAD='(-0.01,0.01)';
      OUTPUT_LOAD='(1.0,-1.0)';
      PINUSE='BI';
    'I2C_4_SDA':
      PIN_NUMBER='(A10)';
      BIDIRECTIONAL='TRUE';
      INPUT_LOAD='(-0.01,0.01)';
      OUTPUT_LOAD='(1.0,-1.0)';
      PINUSE='BI';
    'I2C_5_SCL':
      PIN_NUMBER='(A11)';
      BIDIRECTIONAL='TRUE';
      INPUT_LOAD='(-0.01,0.01)';
      OUTPUT_LOAD='(1.0,-1.0)';
      PINUSE='BI';
    'I2C_5_SDA':
      PIN_NUMBER='(A12)';
      BIDIRECTIONAL='TRUE';
      INPUT_LOAD='(-0.01,0.01)';
      OUTPUT_LOAD='(1.0,-1.0)';
      PINUSE='BI';
    'GND_A13':
      PIN_NUMBER='(A13)';
      PINUSE='POWER';
      NO_LOAD_CHECK='Both';
      NO_IO_CHECK='Both';
      NO_ASSERT_CHECK='TRUE';
      NO_DIR_CHECK='TRUE';
      ALLOW_CONNECT='TRUE';
    'CLK_100M_PCIE_DP':
      PIN_NUMBER='(A14)';
      BIDIRECTIONAL='TRUE';
      INPUT_LOAD='(-0.01,0.01)';
      OUTPUT_LOAD='(1.0,-1.0)';
      PINUSE='BI';
    'CLK_100M_PCIE_DN':
      PIN_NUMBER='(A15)';
      BIDIRECTIONAL='TRUE';
      INPUT_LOAD='(-0.01,0.01)';
      OUTPUT_LOAD='(1.0,-1.0)';
      PINUSE='BI';
    'GND_A16':
      PIN_NUMBER='(A16)';
      PINUSE='POWER';
      NO_LOAD_CHECK='Both';
      NO_IO_CHECK='Both';
      NO_ASSERT_CHECK='TRUE';
      NO_DIR_CHECK='TRUE';
      ALLOW_CONNECT='TRUE';
    'PCIE_BMC_TX_DP':
      PIN_NUMBER='(A17)';
      BIDIRECTIONAL='TRUE';
      INPUT_LOAD='(-0.01,0.01)';
      OUTPUT_LOAD='(1.0,-1.0)';
      PINUSE='BI';
    'PCIE_BMC_TX_DN':
      PIN_NUMBER='(A18)';
      BIDIRECTIONAL='TRUE';
      INPUT_LOAD='(-0.01,0.01)';
      OUTPUT_LOAD='(1.0,-1.0)';
      PINUSE='BI';
    'GND_A19':
      PIN_NUMBER='(A19)';
      PINUSE='POWER';
      NO_LOAD_CHECK='Both';
      NO_IO_CHECK='Both';
      NO_ASSERT_CHECK='TRUE';
      NO_DIR_CHECK='TRUE';
      ALLOW_CONNECT='TRUE';
    'PCIE_BMC_RX_DP':
      PIN_NUMBER='(A20)';
      BIDIRECTIONAL='TRUE';
      INPUT_LOAD='(-0.01,0.01)';
      OUTPUT_LOAD='(1.0,-1.0)';
      PINUSE='BI';
    'PCIE_BMC_RX_DN':
      PIN_NUMBER='(A21)';
      BIDIRECTIONAL='TRUE';
      INPUT_LOAD='(-0.01,0.01)';
      OUTPUT_LOAD='(1.0,-1.0)';
      PINUSE='BI';
    'GND_A22':
      PIN_NUMBER='(A22)';
      PINUSE='POWER';
      NO_LOAD_CHECK='Both';
      NO_IO_CHECK='Both';
      NO_ASSERT_CHECK='TRUE';
      NO_DIR_CHECK='TRUE';
      ALLOW_CONNECT='TRUE';
    'I2C_6_SCL':
      PIN_NUMBER='(A23)';
      BIDIRECTIONAL='TRUE';
      INPUT_LOAD='(-0.01,0.01)';
      OUTPUT_LOAD='(1.0,-1.0)';
      PINUSE='BI';
    'I2C_6_SDA':
      PIN_NUMBER='(A24)';
      BIDIRECTIONAL='TRUE';
      INPUT_LOAD='(-0.01,0.01)';
      OUTPUT_LOAD='(1.0,-1.0)';
      PINUSE='BI';
    'I2C_7_SCL':
      PIN_NUMBER='(A25)';
      BIDIRECTIONAL='TRUE';
      INPUT_LOAD='(-0.01,0.01)';
      OUTPUT_LOAD='(1.0,-1.0)';
      PINUSE='BI';
    'I2C_7_SDA':
      PIN_NUMBER='(A26)';
      BIDIRECTIONAL='TRUE';
      INPUT_LOAD='(-0.01,0.01)';
      OUTPUT_LOAD='(1.0,-1.0)';
      PINUSE='BI';
    'I2C_8_SCL':
      PIN_NUMBER='(A27)';
      BIDIRECTIONAL='TRUE';
      INPUT_LOAD='(-0.01,0.01)';
      OUTPUT_LOAD='(1.0,-1.0)';
      PINUSE='BI';
    'I2C_8_SDA':
      PIN_NUMBER='(A28)';
      BIDIRECTIONAL='TRUE';
      INPUT_LOAD='(-0.01,0.01)';
      OUTPUT_LOAD='(1.0,-1.0)';
      PINUSE='BI';
    'I2C_9_SCL':
      PIN_NUMBER='(A29)';
      BIDIRECTIONAL='TRUE';
      INPUT_LOAD='(-0.01,0.01)';
      OUTPUT_LOAD='(1.0,-1.0)';
      PINUSE='BI';
    'I2C_9_SDA':
      PIN_NUMBER='(A30)';
      BIDIRECTIONAL='TRUE';
      INPUT_LOAD='(-0.01,0.01)';
      OUTPUT_LOAD='(1.0,-1.0)';
      PINUSE='BI';
    'I2C_10_SCL':
      PIN_NUMBER='(A31)';
      BIDIRECTIONAL='TRUE';
      INPUT_LOAD='(-0.01,0.01)';
      OUTPUT_LOAD='(1.0,-1.0)';
      PINUSE='BI';
    'I2C_10_SDA':
      PIN_NUMBER='(A32)';
      BIDIRECTIONAL='TRUE';
      INPUT_LOAD='(-0.01,0.01)';
      OUTPUT_LOAD='(1.0,-1.0)';
      PINUSE='BI';
    'GND_A33':
      PIN_NUMBER='(A33)';
      PINUSE='POWER';
      NO_LOAD_CHECK='Both';
      NO_IO_CHECK='Both';
      NO_ASSERT_CHECK='TRUE';
      NO_DIR_CHECK='TRUE';
      ALLOW_CONNECT='TRUE';
    'JTAG_TCK':
      PIN_NUMBER='(A34)';
      BIDIRECTIONAL='TRUE';
      INPUT_LOAD='(-0.01,0.01)';
      OUTPUT_LOAD='(1.0,-1.0)';
      PINUSE='BI';
    'JTAG_TMS':
      PIN_NUMBER='(A35)';
      BIDIRECTIONAL='TRUE';
      INPUT_LOAD='(-0.01,0.01)';
      OUTPUT_LOAD='(1.0,-1.0)';
      PINUSE='BI';
    'JTAG_TDI':
      PIN_NUMBER='(A36)';
      BIDIRECTIONAL='TRUE';
      INPUT_LOAD='(-0.01,0.01)';
      OUTPUT_LOAD='(1.0,-1.0)';
      PINUSE='BI';
    'JTAG_TDO':
      PIN_NUMBER='(A37)';
      BIDIRECTIONAL='TRUE';
      INPUT_LOAD='(-0.01,0.01)';
      OUTPUT_LOAD='(1.0,-1.0)';
      PINUSE='BI';
    'I2C_11_SCL':
      PIN_NUMBER='(A38)';
      BIDIRECTIONAL='TRUE';
      INPUT_LOAD='(-0.01,0.01)';
      OUTPUT_LOAD='(1.0,-1.0)';
      PINUSE='BI';
    'I2C_11_SDA':
      PIN_NUMBER='(A39)';
      BIDIRECTIONAL='TRUE';
      INPUT_LOAD='(-0.01,0.01)';
      OUTPUT_LOAD='(1.0,-1.0)';
      PINUSE='BI';
    'I2C_12_SCL':
      PIN_NUMBER='(A40)';
      BIDIRECTIONAL='TRUE';
      INPUT_LOAD='(-0.01,0.01)';
      OUTPUT_LOAD='(1.0,-1.0)';
      PINUSE='BI';
    'I2C_12_SDA':
      PIN_NUMBER='(A41)';
      BIDIRECTIONAL='TRUE';
      INPUT_LOAD='(-0.01,0.01)';
      OUTPUT_LOAD='(1.0,-1.0)';
      PINUSE='BI';
    'GND_A42':
      PIN_NUMBER='(A42)';
      PINUSE='POWER';
      NO_LOAD_CHECK='Both';
      NO_IO_CHECK='Both';
      NO_ASSERT_CHECK='TRUE';
      NO_DIR_CHECK='TRUE';
      ALLOW_CONNECT='TRUE';
    'HPM_FW_RECOVERY':
      PIN_NUMBER='(A43)';
      BIDIRECTIONAL='TRUE';
      INPUT_LOAD='(-0.01,0.01)';
      OUTPUT_LOAD='(1.0,-1.0)';
      PINUSE='BI';
    'HPM_STBY_RDY':
      PIN_NUMBER='(A44)';
      BIDIRECTIONAL='TRUE';
      INPUT_LOAD='(-0.01,0.01)';
      OUTPUT_LOAD='(1.0,-1.0)';
      PINUSE='BI';
    'HPM_STBY_EN':
      PIN_NUMBER='(A45)';
      BIDIRECTIONAL='TRUE';
      INPUT_LOAD='(-0.01,0.01)';
      OUTPUT_LOAD='(1.0,-1.0)';
      PINUSE='BI';
    'HPM_STBY_RST_N':
      PIN_NUMBER='(A46)';
      BIDIRECTIONAL='TRUE';
      INPUT_LOAD='(-0.01,0.01)';
      OUTPUT_LOAD='(1.0,-1.0)';
      PINUSE='BI';
    'SYS_PWRBTN_N':
      PIN_NUMBER='(A47)';
      BIDIRECTIONAL='TRUE';
      INPUT_LOAD='(-0.01,0.01)';
      OUTPUT_LOAD='(1.0,-1.0)';
      PINUSE='BI';
    'SYS_PWROK':
      PIN_NUMBER='(A48)';
      BIDIRECTIONAL='TRUE';
      INPUT_LOAD='(-0.01,0.01)';
      OUTPUT_LOAD='(1.0,-1.0)';
      PINUSE='BI';
    'DBP_PREQ_N':
      PIN_NUMBER='(A49)';
      BIDIRECTIONAL='TRUE';
      INPUT_LOAD='(-0.01,0.01)';
      OUTPUT_LOAD='(1.0,-1.0)';
      PINUSE='BI';
    'DBP_PRDY_N':
      PIN_NUMBER='(A50)';
      BIDIRECTIONAL='TRUE';
      INPUT_LOAD='(-0.01,0.01)';
      OUTPUT_LOAD='(1.0,-1.0)';
      PINUSE='BI';
    'RST_PLTRST_BUF_N':
      PIN_NUMBER='(A51)';
      BIDIRECTIONAL='TRUE';
      INPUT_LOAD='(-0.01,0.01)';
      OUTPUT_LOAD='(1.0,-1.0)';
      PINUSE='BI';
    'SPARE1':
      PIN_NUMBER='(A52)';
      BIDIRECTIONAL='TRUE';
      INPUT_LOAD='(-0.01,0.01)';
      OUTPUT_LOAD='(1.0,-1.0)';
      PINUSE='BI';
    'ROT_CPU_RST_N':
      PIN_NUMBER='(A53)';
      BIDIRECTIONAL='TRUE';
      INPUT_LOAD='(-0.01,0.01)';
      OUTPUT_LOAD='(1.0,-1.0)';
      PINUSE='BI';
    'CHASI_N':
      PIN_NUMBER='(A54)';
      BIDIRECTIONAL='TRUE';
      INPUT_LOAD='(-0.01,0.01)';
      OUTPUT_LOAD='(1.0,-1.0)';
      PINUSE='BI';
    'SPARE0':
      PIN_NUMBER='(A55)';
      BIDIRECTIONAL='TRUE';
      INPUT_LOAD='(-0.01,0.01)';
      OUTPUT_LOAD='(1.0,-1.0)';
      PINUSE='BI';
    'IRQ_N':
      PIN_NUMBER='(A56)';
      BIDIRECTIONAL='TRUE';
      INPUT_LOAD='(-0.01,0.01)';
      OUTPUT_LOAD='(1.0,-1.0)';
      PINUSE='BI';
    'PRSNT1_N':
      PIN_NUMBER='(A57)';
      BIDIRECTIONAL='TRUE';
      INPUT_LOAD='(-0.01,0.01)';
      OUTPUT_LOAD='(1.0,-1.0)';
      PINUSE='BI';
    'GND_A58':
      PIN_NUMBER='(A58)';
      PINUSE='POWER';
      NO_LOAD_CHECK='Both';
      NO_IO_CHECK='Both';
      NO_ASSERT_CHECK='TRUE';
      NO_DIR_CHECK='TRUE';
      ALLOW_CONNECT='TRUE';
    'PCIE_HPM_RXP_0':
      PIN_NUMBER='(A59)';
      BIDIRECTIONAL='TRUE';
      INPUT_LOAD='(-0.01,0.01)';
      OUTPUT_LOAD='(1.0,-1.0)';
      PINUSE='BI';
    'PCIE_HPM_RXN_0':
      PIN_NUMBER='(A60)';
      BIDIRECTIONAL='TRUE';
      INPUT_LOAD='(-0.01,0.01)';
      OUTPUT_LOAD='(1.0,-1.0)';
      PINUSE='BI';
    'GND_A61':
      PIN_NUMBER='(A61)';
      PINUSE='POWER';
      NO_LOAD_CHECK='Both';
      NO_IO_CHECK='Both';
      NO_ASSERT_CHECK='TRUE';
      NO_DIR_CHECK='TRUE';
      ALLOW_CONNECT='TRUE';
    'PCIE_HPM_RXP_1':
      PIN_NUMBER='(A62)';
      BIDIRECTIONAL='TRUE';
      INPUT_LOAD='(-0.01,0.01)';
      OUTPUT_LOAD='(1.0,-1.0)';
      PINUSE='BI';
    'PCIE_HPM_RXN_1':
      PIN_NUMBER='(A63)';
      BIDIRECTIONAL='TRUE';
      INPUT_LOAD='(-0.01,0.01)';
      OUTPUT_LOAD='(1.0,-1.0)';
      PINUSE='BI';
    'GND_A64':
      PIN_NUMBER='(A64)';
      PINUSE='POWER';
      NO_LOAD_CHECK='Both';
      NO_IO_CHECK='Both';
      NO_ASSERT_CHECK='TRUE';
      NO_DIR_CHECK='TRUE';
      ALLOW_CONNECT='TRUE';
    'PCIE_HPM_RXP_2':
      PIN_NUMBER='(A65)';
      BIDIRECTIONAL='TRUE';
      INPUT_LOAD='(-0.01,0.01)';
      OUTPUT_LOAD='(1.0,-1.0)';
      PINUSE='BI';
    'PCIE_HPM_RXN_2':
      PIN_NUMBER='(A66)';
      BIDIRECTIONAL='TRUE';
      INPUT_LOAD='(-0.01,0.01)';
      OUTPUT_LOAD='(1.0,-1.0)';
      PINUSE='BI';
    'GND_A67':
      PIN_NUMBER='(A67)';
      PINUSE='POWER';
      NO_LOAD_CHECK='Both';
      NO_IO_CHECK='Both';
      NO_ASSERT_CHECK='TRUE';
      NO_DIR_CHECK='TRUE';
      ALLOW_CONNECT='TRUE';
    'PCIE_HPM_RXP_3':
      PIN_NUMBER='(A68)';
      BIDIRECTIONAL='TRUE';
      INPUT_LOAD='(-0.01,0.01)';
      OUTPUT_LOAD='(1.0,-1.0)';
      PINUSE='BI';
    'PCIE_HPM_RXN_3':
      PIN_NUMBER='(A69)';
      BIDIRECTIONAL='TRUE';
      INPUT_LOAD='(-0.01,0.01)';
      OUTPUT_LOAD='(1.0,-1.0)';
      PINUSE='BI';
    'GND_A70':
      PIN_NUMBER='(A70)';
      PINUSE='POWER';
      NO_LOAD_CHECK='Both';
      NO_IO_CHECK='Both';
      NO_ASSERT_CHECK='TRUE';
      NO_DIR_CHECK='TRUE';
      ALLOW_CONNECT='TRUE';
    'P12V_AUX_OB1':
      PIN_NUMBER='(OB1)';
      PINUSE='POWER';
      NO_LOAD_CHECK='Both';
      NO_IO_CHECK='Both';
      NO_ASSERT_CHECK='TRUE';
      NO_DIR_CHECK='TRUE';
      ALLOW_CONNECT='TRUE';
    'P12V_AUX_OB2':
      PIN_NUMBER='(OB2)';
      PINUSE='POWER';
      NO_LOAD_CHECK='Both';
      NO_IO_CHECK='Both';
      NO_ASSERT_CHECK='TRUE';
      NO_DIR_CHECK='TRUE';
      ALLOW_CONNECT='TRUE';
    'PRSNT0_N':
      PIN_NUMBER='(OB3)';
      BIDIRECTIONAL='TRUE';
      INPUT_LOAD='(-0.01,0.01)';
      OUTPUT_LOAD='(1.0,-1.0)';
      PINUSE='BI';
    'GND_OB4':
      PIN_NUMBER='(OB4)';
      PINUSE='POWER';
      NO_LOAD_CHECK='Both';
      NO_IO_CHECK='Both';
      NO_ASSERT_CHECK='TRUE';
      NO_DIR_CHECK='TRUE';
      ALLOW_CONNECT='TRUE';
    'UART1_SCM_TX':
      PIN_NUMBER='(OB5)';
      BIDIRECTIONAL='TRUE';
      INPUT_LOAD='(-0.01,0.01)';
      OUTPUT_LOAD='(1.0,-1.0)';
      PINUSE='BI';
    'UART1_SCM_RX':
      PIN_NUMBER='(OB6)';
      BIDIRECTIONAL='TRUE';
      INPUT_LOAD='(-0.01,0.01)';
      OUTPUT_LOAD='(1.0,-1.0)';
      PINUSE='BI';
    'GND_OB7':
      PIN_NUMBER='(OB7)';
      PINUSE='POWER';
      NO_LOAD_CHECK='Both';
      NO_IO_CHECK='Both';
      NO_ASSERT_CHECK='TRUE';
      NO_DIR_CHECK='TRUE';
      ALLOW_CONNECT='TRUE';
    'UART0_SCM_TX':
      PIN_NUMBER='(OB8)';
      BIDIRECTIONAL='TRUE';
      INPUT_LOAD='(-0.01,0.01)';
      OUTPUT_LOAD='(1.0,-1.0)';
      PINUSE='BI';
    'UART0_SCM_RX':
      PIN_NUMBER='(OB9)';
      BIDIRECTIONAL='TRUE';
      INPUT_LOAD='(-0.01,0.01)';
      OUTPUT_LOAD='(1.0,-1.0)';
      PINUSE='BI';
    'GND_OB10':
      PIN_NUMBER='(OB10)';
      PINUSE='POWER';
      NO_LOAD_CHECK='Both';
      NO_IO_CHECK='Both';
      NO_ASSERT_CHECK='TRUE';
      NO_DIR_CHECK='TRUE';
      ALLOW_CONNECT='TRUE';
    'SPI0_CLK':
      PIN_NUMBER='(OB11)';
      BIDIRECTIONAL='TRUE';
      INPUT_LOAD='(-0.01,0.01)';
      OUTPUT_LOAD='(1.0,-1.0)';
      PINUSE='BI';
    'SPI0_CS_N':
      PIN_NUMBER='(OB12)';
      BIDIRECTIONAL='TRUE';
      INPUT_LOAD='(-0.01,0.01)';
      OUTPUT_LOAD='(1.0,-1.0)';
      PINUSE='BI';
    'SPI0_MOSI':
      PIN_NUMBER='(OB13)';
      BIDIRECTIONAL='TRUE';
      INPUT_LOAD='(-0.01,0.01)';
      OUTPUT_LOAD='(1.0,-1.0)';
      PINUSE='BI';
    'SPI0_MISO':
      PIN_NUMBER='(OB14)';
      BIDIRECTIONAL='TRUE';
      INPUT_LOAD='(-0.01,0.01)';
      OUTPUT_LOAD='(1.0,-1.0)';
      PINUSE='BI';
    'ESPI_CLK':
      PIN_NUMBER='(B1)';
      BIDIRECTIONAL='TRUE';
      INPUT_LOAD='(-0.01,0.01)';
      OUTPUT_LOAD='(1.0,-1.0)';
      PINUSE='BI';
    'ESPI_CS0_N':
      PIN_NUMBER='(B2)';
      BIDIRECTIONAL='TRUE';
      INPUT_LOAD='(-0.01,0.01)';
      OUTPUT_LOAD='(1.0,-1.0)';
      PINUSE='BI';
    'ESPI_ALERT_N':
      PIN_NUMBER='(B3)';
      BIDIRECTIONAL='TRUE';
      INPUT_LOAD='(-0.01,0.01)';
      OUTPUT_LOAD='(1.0,-1.0)';
      PINUSE='BI';
    'ESPI_RESET_N':
      PIN_NUMBER='(B4)';
      BIDIRECTIONAL='TRUE';
      INPUT_LOAD='(-0.01,0.01)';
      OUTPUT_LOAD='(1.0,-1.0)';
      PINUSE='BI';
    'ESPI_IO0':
      PIN_NUMBER='(B5)';
      BIDIRECTIONAL='TRUE';
      INPUT_LOAD='(-0.01,0.01)';
      OUTPUT_LOAD='(1.0,-1.0)';
      PINUSE='BI';
    'ESPI_IO1':
      PIN_NUMBER='(B6)';
      BIDIRECTIONAL='TRUE';
      INPUT_LOAD='(-0.01,0.01)';
      OUTPUT_LOAD='(1.0,-1.0)';
      PINUSE='BI';
    'ESPI_IO2':
      PIN_NUMBER='(B7)';
      BIDIRECTIONAL='TRUE';
      INPUT_LOAD='(-0.01,0.01)';
      OUTPUT_LOAD='(1.0,-1.0)';
      PINUSE='BI';
    'ESPI_IO3':
      PIN_NUMBER='(B8)';
      BIDIRECTIONAL='TRUE';
      INPUT_LOAD='(-0.01,0.01)';
      OUTPUT_LOAD='(1.0,-1.0)';
      PINUSE='BI';
    'RSVD3':
      PIN_NUMBER='(B9)';
      BIDIRECTIONAL='TRUE';
      INPUT_LOAD='(-0.01,0.01)';
      OUTPUT_LOAD='(1.0,-1.0)';
      PINUSE='BI';
    'GND_B10':
      PIN_NUMBER='(B10)';
      PINUSE='POWER';
      NO_LOAD_CHECK='Both';
      NO_IO_CHECK='Both';
      NO_ASSERT_CHECK='TRUE';
      NO_DIR_CHECK='TRUE';
      ALLOW_CONNECT='TRUE';
    'QSPI0_CLK':
      PIN_NUMBER='(B11)';
      BIDIRECTIONAL='TRUE';
      INPUT_LOAD='(-0.01,0.01)';
      OUTPUT_LOAD='(1.0,-1.0)';
      PINUSE='BI';
    'QSPI0_CS0_N':
      PIN_NUMBER='(B12)';
      BIDIRECTIONAL='TRUE';
      INPUT_LOAD='(-0.01,0.01)';
      OUTPUT_LOAD='(1.0,-1.0)';
      PINUSE='BI';
    'QSPI0_D0':
      PIN_NUMBER='(B13)';
      BIDIRECTIONAL='TRUE';
      INPUT_LOAD='(-0.01,0.01)';
      OUTPUT_LOAD='(1.0,-1.0)';
      PINUSE='BI';
    'QSPI0_D1':
      PIN_NUMBER='(B14)';
      BIDIRECTIONAL='TRUE';
      INPUT_LOAD='(-0.01,0.01)';
      OUTPUT_LOAD='(1.0,-1.0)';
      PINUSE='BI';
    'QSPI0_D2':
      PIN_NUMBER='(B15)';
      BIDIRECTIONAL='TRUE';
      INPUT_LOAD='(-0.01,0.01)';
      OUTPUT_LOAD='(1.0,-1.0)';
      PINUSE='BI';
    'QSPI0_D3':
      PIN_NUMBER='(B16)';
      BIDIRECTIONAL='TRUE';
      INPUT_LOAD='(-0.01,0.01)';
      OUTPUT_LOAD='(1.0,-1.0)';
      PINUSE='BI';
    'GND_B17':
      PIN_NUMBER='(B17)';
      PINUSE='POWER';
      NO_LOAD_CHECK='Both';
      NO_IO_CHECK='Both';
      NO_ASSERT_CHECK='TRUE';
      NO_DIR_CHECK='TRUE';
      ALLOW_CONNECT='TRUE';
    'NCSI_CLK':
      PIN_NUMBER='(B18)';
      BIDIRECTIONAL='TRUE';
      INPUT_LOAD='(-0.01,0.01)';
      OUTPUT_LOAD='(1.0,-1.0)';
      PINUSE='BI';
    'NCSI_CRS_DV':
      PIN_NUMBER='(B19)';
      BIDIRECTIONAL='TRUE';
      INPUT_LOAD='(-0.01,0.01)';
      OUTPUT_LOAD='(1.0,-1.0)';
      PINUSE='BI';
    'NCSI_TXEN':
      PIN_NUMBER='(B20)';
      BIDIRECTIONAL='TRUE';
      INPUT_LOAD='(-0.01,0.01)';
      OUTPUT_LOAD='(1.0,-1.0)';
      PINUSE='BI';
    'NCSI_TXD0':
      PIN_NUMBER='(B21)';
      BIDIRECTIONAL='TRUE';
      INPUT_LOAD='(-0.01,0.01)';
      OUTPUT_LOAD='(1.0,-1.0)';
      PINUSE='BI';
    'NCSI_TXD1':
      PIN_NUMBER='(B22)';
      BIDIRECTIONAL='TRUE';
      INPUT_LOAD='(-0.01,0.01)';
      OUTPUT_LOAD='(1.0,-1.0)';
      PINUSE='BI';
    'NCSI_RXER':
      PIN_NUMBER='(B23)';
      BIDIRECTIONAL='TRUE';
      INPUT_LOAD='(-0.01,0.01)';
      OUTPUT_LOAD='(1.0,-1.0)';
      PINUSE='BI';
    'NCSI_RXD0':
      PIN_NUMBER='(B24)';
      BIDIRECTIONAL='TRUE';
      INPUT_LOAD='(-0.01,0.01)';
      OUTPUT_LOAD='(1.0,-1.0)';
      PINUSE='BI';
    'NCSI_RXD1':
      PIN_NUMBER='(B25)';
      BIDIRECTIONAL='TRUE';
      INPUT_LOAD='(-0.01,0.01)';
      OUTPUT_LOAD='(1.0,-1.0)';
      PINUSE='BI';
    'GND_B26':
      PIN_NUMBER='(B26)';
      PINUSE='POWER';
      NO_LOAD_CHECK='Both';
      NO_IO_CHECK='Both';
      NO_ASSERT_CHECK='TRUE';
      NO_DIR_CHECK='TRUE';
      ALLOW_CONNECT='TRUE';
    'PECI_BMC':
      PIN_NUMBER='(B27)';
      BIDIRECTIONAL='TRUE';
      INPUT_LOAD='(-0.01,0.01)';
      OUTPUT_LOAD='(1.0,-1.0)';
      PINUSE='BI';
    'PVCCIO_PECI':
      PIN_NUMBER='(B28)';
      PINUSE='POWER';
      NO_LOAD_CHECK='Both';
      NO_IO_CHECK='Both';
      NO_ASSERT_CHECK='TRUE';
      NO_DIR_CHECK='TRUE';
      ALLOW_CONNECT='TRUE';
    'SGPIO0_DO':
      PIN_NUMBER='(B29)';
      BIDIRECTIONAL='TRUE';
      INPUT_LOAD='(-0.01,0.01)';
      OUTPUT_LOAD='(1.0,-1.0)';
      PINUSE='BI';
    'SGPIO_CLK':
      PIN_NUMBER='(B30)';
      BIDIRECTIONAL='TRUE';
      INPUT_LOAD='(-0.01,0.01)';
      OUTPUT_LOAD='(1.0,-1.0)';
      PINUSE='BI';
    'SGPIO0_DI':
      PIN_NUMBER='(B31)';
      BIDIRECTIONAL='TRUE';
      INPUT_LOAD='(-0.01,0.01)';
      OUTPUT_LOAD='(1.0,-1.0)';
      PINUSE='BI';
    'SGPIO0_LD':
      PIN_NUMBER='(B32)';
      BIDIRECTIONAL='TRUE';
      INPUT_LOAD='(-0.01,0.01)';
      OUTPUT_LOAD='(1.0,-1.0)';
      PINUSE='BI';
    'GND_B33':
      PIN_NUMBER='(B33)';
      PINUSE='POWER';
      NO_LOAD_CHECK='Both';
      NO_IO_CHECK='Both';
      NO_ASSERT_CHECK='TRUE';
      NO_DIR_CHECK='TRUE';
      ALLOW_CONNECT='TRUE';
    'SGPIO1_DO':
      PIN_NUMBER='(B34)';
      BIDIRECTIONAL='TRUE';
      INPUT_LOAD='(-0.01,0.01)';
      OUTPUT_LOAD='(1.0,-1.0)';
      PINUSE='BI';
    'RSVD2':
      PIN_NUMBER='(B35)';
      OUTPUT_TYPE='(TS,TS)';
      INPUT_LOAD='(-0.01,0.01)';
      OUTPUT_LOAD='(1.0,-1.0)';
      PINUSE='TRI';
    'SGPIO1_DI':
      PIN_NUMBER='(B36)';
      BIDIRECTIONAL='TRUE';
      INPUT_LOAD='(-0.01,0.01)';
      OUTPUT_LOAD='(1.0,-1.0)';
      PINUSE='BI';
    'SGPIO1_LD':
      PIN_NUMBER='(B37)';
      BIDIRECTIONAL='TRUE';
      INPUT_LOAD='(-0.01,0.01)';
      OUTPUT_LOAD='(1.0,-1.0)';
      PINUSE='BI';
    'GND_B38':
      PIN_NUMBER='(B38)';
      PINUSE='POWER';
      NO_LOAD_CHECK='Both';
      NO_IO_CHECK='Both';
      NO_ASSERT_CHECK='TRUE';
      NO_DIR_CHECK='TRUE';
      ALLOW_CONNECT='TRUE';
    'SGPIO_RESET_N':
      PIN_NUMBER='(B39)';
      BIDIRECTIONAL='TRUE';
      INPUT_LOAD='(-0.01,0.01)';
      OUTPUT_LOAD='(1.0,-1.0)';
      PINUSE='BI';
    'SGPIO_INTR_N':
      PIN_NUMBER='(B40)';
      BIDIRECTIONAL='TRUE';
      INPUT_LOAD='(-0.01,0.01)';
      OUTPUT_LOAD='(1.0,-1.0)';
      PINUSE='BI';
    'P3V0_BAT':
      PIN_NUMBER='(B41)';
      PINUSE='POWER';
      NO_LOAD_CHECK='Both';
      NO_IO_CHECK='Both';
      NO_ASSERT_CHECK='TRUE';
      NO_DIR_CHECK='TRUE';
      ALLOW_CONNECT='TRUE';
    'QSPI0_CS1_N':
      PIN_NUMBER='(B42)';
      BIDIRECTIONAL='TRUE';
      INPUT_LOAD='(-0.01,0.01)';
      OUTPUT_LOAD='(1.0,-1.0)';
      PINUSE='BI';
    'QSPI1_CLK':
      PIN_NUMBER='(B43)';
      BIDIRECTIONAL='TRUE';
      INPUT_LOAD='(-0.01,0.01)';
      OUTPUT_LOAD='(1.0,-1.0)';
      PINUSE='BI';
    'QSPI1_CS0_N':
      PIN_NUMBER='(B44)';
      BIDIRECTIONAL='TRUE';
      INPUT_LOAD='(-0.01,0.01)';
      OUTPUT_LOAD='(1.0,-1.0)';
      PINUSE='BI';
    'QSPI1_D0':
      PIN_NUMBER='(B45)';
      BIDIRECTIONAL='TRUE';
      INPUT_LOAD='(-0.01,0.01)';
      OUTPUT_LOAD='(1.0,-1.0)';
      PINUSE='BI';
    'QSPI1_D1':
      PIN_NUMBER='(B46)';
      BIDIRECTIONAL='TRUE';
      INPUT_LOAD='(-0.01,0.01)';
      OUTPUT_LOAD='(1.0,-1.0)';
      PINUSE='BI';
    'QSPI1_D2':
      PIN_NUMBER='(B47)';
      BIDIRECTIONAL='TRUE';
      INPUT_LOAD='(-0.01,0.01)';
      OUTPUT_LOAD='(1.0,-1.0)';
      PINUSE='BI';
    'QSPI1_D3':
      PIN_NUMBER='(B48)';
      BIDIRECTIONAL='TRUE';
      INPUT_LOAD='(-0.01,0.01)';
      OUTPUT_LOAD='(1.0,-1.0)';
      PINUSE='BI';
    'GND_B49':
      PIN_NUMBER='(B49)';
      PINUSE='POWER';
      NO_LOAD_CHECK='Both';
      NO_IO_CHECK='Both';
      NO_ASSERT_CHECK='TRUE';
      NO_DIR_CHECK='TRUE';
      ALLOW_CONNECT='TRUE';
    'USB2_DP':
      PIN_NUMBER='(B50)';
      BIDIRECTIONAL='TRUE';
      INPUT_LOAD='(-0.01,0.01)';
      OUTPUT_LOAD='(1.0,-1.0)';
      PINUSE='BI';
    'USB2_DN':
      PIN_NUMBER='(B51)';
      BIDIRECTIONAL='TRUE';
      INPUT_LOAD='(-0.01,0.01)';
      OUTPUT_LOAD='(1.0,-1.0)';
      PINUSE='BI';
    'GND_B52':
      PIN_NUMBER='(B52)';
      PINUSE='POWER';
      NO_LOAD_CHECK='Both';
      NO_IO_CHECK='Both';
      NO_ASSERT_CHECK='TRUE';
      NO_DIR_CHECK='TRUE';
      ALLOW_CONNECT='TRUE';
    'USB1_DP':
      PIN_NUMBER='(B53)';
      BIDIRECTIONAL='TRUE';
      INPUT_LOAD='(-0.01,0.01)';
      OUTPUT_LOAD='(1.0,-1.0)';
      PINUSE='BI';
    'USB1_DN':
      PIN_NUMBER='(B54)';
      BIDIRECTIONAL='TRUE';
      INPUT_LOAD='(-0.01,0.01)';
      OUTPUT_LOAD='(1.0,-1.0)';
      PINUSE='BI';
    'GND_B55':
      PIN_NUMBER='(B55)';
      PINUSE='POWER';
      NO_LOAD_CHECK='Both';
      NO_IO_CHECK='Both';
      NO_ASSERT_CHECK='TRUE';
      NO_DIR_CHECK='TRUE';
      ALLOW_CONNECT='TRUE';
    'RSVD0':
      PIN_NUMBER='(B56)';
      OUTPUT_TYPE='(TS,TS)';
      INPUT_LOAD='(-0.01,0.01)';
      OUTPUT_LOAD='(1.0,-1.0)';
      PINUSE='TRI';
    'RSVD1':
      PIN_NUMBER='(B57)';
      OUTPUT_TYPE='(TS,TS)';
      INPUT_LOAD='(-0.01,0.01)';
      OUTPUT_LOAD='(1.0,-1.0)';
      PINUSE='TRI';
    'GND_B58':
      PIN_NUMBER='(B58)';
      PINUSE='POWER';
      NO_LOAD_CHECK='Both';
      NO_IO_CHECK='Both';
      NO_ASSERT_CHECK='TRUE';
      NO_DIR_CHECK='TRUE';
      ALLOW_CONNECT='TRUE';
    'PCIE_HPM_TXP_0':
      PIN_NUMBER='(B59)';
      BIDIRECTIONAL='TRUE';
      INPUT_LOAD='(-0.01,0.01)';
      OUTPUT_LOAD='(1.0,-1.0)';
      PINUSE='BI';
    'PCIE_HPM_TXN_0':
      PIN_NUMBER='(B60)';
      BIDIRECTIONAL='TRUE';
      INPUT_LOAD='(-0.01,0.01)';
      OUTPUT_LOAD='(1.0,-1.0)';
      PINUSE='BI';
    'GND_B61':
      PIN_NUMBER='(B61)';
      PINUSE='POWER';
      NO_LOAD_CHECK='Both';
      NO_IO_CHECK='Both';
      NO_ASSERT_CHECK='TRUE';
      NO_DIR_CHECK='TRUE';
      ALLOW_CONNECT='TRUE';
    'PCIE_HPM_TXP_1':
      PIN_NUMBER='(B62)';
      BIDIRECTIONAL='TRUE';
      INPUT_LOAD='(-0.01,0.01)';
      OUTPUT_LOAD='(1.0,-1.0)';
      PINUSE='BI';
    'PCIE_HPM_TXN_1':
      PIN_NUMBER='(B63)';
      BIDIRECTIONAL='TRUE';
      INPUT_LOAD='(-0.01,0.01)';
      OUTPUT_LOAD='(1.0,-1.0)';
      PINUSE='BI';
    'GND_B64':
      PIN_NUMBER='(B64)';
      PINUSE='POWER';
      NO_LOAD_CHECK='Both';
      NO_IO_CHECK='Both';
      NO_ASSERT_CHECK='TRUE';
      NO_DIR_CHECK='TRUE';
      ALLOW_CONNECT='TRUE';
    'PCIE_HPM_TXP_2':
      PIN_NUMBER='(B65)';
      BIDIRECTIONAL='TRUE';
      INPUT_LOAD='(-0.01,0.01)';
      OUTPUT_LOAD='(1.0,-1.0)';
      PINUSE='BI';
    'PCIE_HPM_TXN_2':
      PIN_NUMBER='(B66)';
      BIDIRECTIONAL='TRUE';
      INPUT_LOAD='(-0.01,0.01)';
      OUTPUT_LOAD='(1.0,-1.0)';
      PINUSE='BI';
    'GND_B67':
      PIN_NUMBER='(B67)';
      PINUSE='POWER';
      NO_LOAD_CHECK='Both';
      NO_IO_CHECK='Both';
      NO_ASSERT_CHECK='TRUE';
      NO_DIR_CHECK='TRUE';
      ALLOW_CONNECT='TRUE';
    'PCIE_HPM_TXP_3':
      PIN_NUMBER='(B68)';
      BIDIRECTIONAL='TRUE';
      INPUT_LOAD='(-0.01,0.01)';
      OUTPUT_LOAD='(1.0,-1.0)';
      PINUSE='BI';
    'PCIE_HPM_TXN_3':
      PIN_NUMBER='(B69)';
      BIDIRECTIONAL='TRUE';
      INPUT_LOAD='(-0.01,0.01)';
      OUTPUT_LOAD='(1.0,-1.0)';
      PINUSE='BI';
    'GND_B70':
      PIN_NUMBER='(B70)';
      PINUSE='POWER';
      NO_LOAD_CHECK='Both';
      NO_IO_CHECK='Both';
      NO_ASSERT_CHECK='TRUE';
      NO_DIR_CHECK='TRUE';
      ALLOW_CONNECT='TRUE';
  end_pin;
  body
      PART_NAME='FCONN168_ME1016810202011_SCM';
      BODY_NAME='FCONN168_ME1016810202011_SCM';
      PHYS_DES_PREFIX='GF';
      CLASS='IO';
      STANDARD='';
      LIFECYCLE='';
      JEDEC_TYPE='GOLD_168P_ME1016813401311';
      ALT_SYMBOLS='';
      DESCRIPTION='GOLD_168P_ME1016810202011_SCM';
      MANUFTR='APL';
      MANUF_PN='';
      RD_CMPLS_LVL='';
      CMPLS_LVL='';
      DIP_SMD='';
      FROM_PJ='F0T-IVES';
      DATA='APL_ME1016810202011.pdf';
      FP_ECN='GOLD_168P_ME1016810202011.msg';
      EE_CHECK_LIST='';
      STATUS='';
      PSL='';
      PREFERENCE='';
      CREATOR='';
      CREATEDAY='20211108';
      ESD_CDM='';
      ESD_HBM='';
      ESD_MM='';
      MSD='';
      PIN_LENGTH_LONG_PIN='';
      PIN_LENGTH_SHORT_PIN='';
      PARENT_PART_TYPE='FCONN168_ME1016810202011_SCM';
      PARENT_PPT='FCONN168_ME1016810202011_SCM';
      PARENT_PPT_PART='FCONN168_ME1016810202011_SCM-FCONN168_ME1016810202011_SCM,SMLF,EMPTY,GOLD244';
  end_body;
end_primitive;
primitive 'FSA3357K8X-FSA3357K8X,SMLF,IC,A';
  pin
    'A':
      PIN_NUMBER='(7)';
      BIDIRECTIONAL='TRUE';
      INPUT_LOAD='(-0.01,0.01)';
      OUTPUT_LOAD='(1.0,-1.0)';
      PINUSE='BI';
    'GND':
      PIN_NUMBER='(4)';
      PINUSE='POWER';
      NO_LOAD_CHECK='Both';
      NO_IO_CHECK='Both';
      NO_ASSERT_CHECK='TRUE';
      NO_DIR_CHECK='TRUE';
      ALLOW_CONNECT='TRUE';
    'B2':
      PIN_NUMBER='(3)';
      BIDIRECTIONAL='TRUE';
      INPUT_LOAD='(-0.01,0.01)';
      OUTPUT_LOAD='(1.0,-1.0)';
      PINUSE='BI';
    'S2':
      PIN_NUMBER='(5)';
      INPUT_LOAD='(-0.01,0.01)';
      PINUSE='IN';
    'VCC':
      PIN_NUMBER='(8)';
      PINUSE='POWER';
      NO_LOAD_CHECK='Both';
      NO_IO_CHECK='Both';
      NO_ASSERT_CHECK='TRUE';
      NO_DIR_CHECK='TRUE';
      ALLOW_CONNECT='TRUE';
    'B1':
      PIN_NUMBER='(2)';
      BIDIRECTIONAL='TRUE';
      INPUT_LOAD='(-0.01,0.01)';
      OUTPUT_LOAD='(1.0,-1.0)';
      PINUSE='BI';
    'B0':
      PIN_NUMBER='(1)';
      BIDIRECTIONAL='TRUE';
      INPUT_LOAD='(-0.01,0.01)';
      OUTPUT_LOAD='(1.0,-1.0)';
      PINUSE='BI';
    'S1':
      PIN_NUMBER='(6)';
      INPUT_LOAD='(-0.01,0.01)';
      PINUSE='IN';
  end_pin;
  body
      PART_NAME='FSA3357K8X';
      BODY_NAME='FSA3357K8X';
      PHYS_DES_PREFIX='U';
      CLASS='IC';
      STANDARD='Potential';
      LIFECYCLE='End of Life';
      JEDEC_TYPE='US8_0-5_2X2-3_EOL';
      DESCRIPTION='IC OTHER(8P)FSA3357K8X(US8)';
      MANUFTR='FAC';
      MANUF_PN='FSA3357K8X';
      RD_CMPLS_LVL='EP';
      CMPLS_LVL='';
      FROM_PJ='S1U-OWEN';
      DIP_SMD='';
      DATA='FAC_FSA3357K8X.pdf';
      EE_CHECK_LIST='';
      FP_ECN='';
      PSL='';
      CREATOR='';
      STATUS='';
      CREATEDAY='20150622';
      PARENT_PART_TYPE='FSA3357K8X';
      PARENT_PPT='FSA3357K8X';
      PARENT_PPT_PART='FSA3357K8X-FSA3357K8X,SMLF,IC,AL003357009';
  end_body;
end_primitive;
primitive 'HOLE_TH-EMPTY,DUMMY50';
  pin
    '1':
      PIN_NUMBER='(1)';
      INPUT_LOAD='(-0.01,0.01)';
      OUTPUT_LOAD='(1.0,-1.0)';
      BIDIRECTIONAL='TRUE';
      PINUSE='BI';
  end_pin;
  body
      CLASS='IO';
      PART_NAME='HOLE';
      PHYS_DES_PREFIX='H';
      STANDARD='';
      LIFECYCLE='';
      JEDEC_TYPE='HOLE_TOOLINGD125N_T2-0';
      DESCRIPTION='HOLE_TOOLINGD125N_T2-0';
      COMPONENT_TYPE='';
      LEAD_LENGTH='';
      DFM_EXCLUSION='';
      PARENT_PART_TYPE='HOLE';
      PARENT_PPT='HOLE';
      PARENT_PPT_PART='HOLE_TH-EMPTY,DUMMY50';
  end_body;
end_primitive;
primitive 'HOLE_TH-EMPTY,HOLE1211';
  pin
    '1':
      PIN_NUMBER='(1)';
      INPUT_LOAD='(-0.01,0.01)';
      OUTPUT_LOAD='(1.0,-1.0)';
      BIDIRECTIONAL='TRUE';
      PINUSE='BI';
  end_pin;
  body
      CLASS='IO';
      PART_NAME='HOLE';
      PHYS_DES_PREFIX='H';
      STANDARD='';
      LIFECYCLE='';
      JEDEC_TYPE='HOLE_C6-03D3-13B6-03_NPB';
      DESCRIPTION='HOLE_C6-03D3-13B6-03_NPB';
      COMPONENT_TYPE='';
      LEAD_LENGTH='';
      DFM_EXCLUSION='';
      PARENT_PART_TYPE='HOLE';
      PARENT_PPT='HOLE';
      PARENT_PPT_PART='HOLE_TH-EMPTY,HOLE1211';
  end_body;
end_primitive;
primitive 'HOLE_TH-EMPTY,HOLE1247';
  pin
    '1':
      PIN_NUMBER='(1)';
      INPUT_LOAD='(-0.01,0.01)';
      OUTPUT_LOAD='(1.0,-1.0)';
      BIDIRECTIONAL='TRUE';
      PINUSE='BI';
  end_pin;
  body
      CLASS='IO';
      PART_NAME='HOLE';
      PHYS_DES_PREFIX='H';
      STANDARD='';
      LIFECYCLE='';
      JEDEC_TYPE='H_OB6-4X8OBD3-2X4-8B6-4X8N_RO6X7-6_NPM';
      DESCRIPTION='HOLE_OB6-4X8OBD3-2X4-8B6-4X8N_RO6X7-6_NPM';
      COMPONENT_TYPE='';
      LEAD_LENGTH='';
      DFM_EXCLUSION='';
      PARENT_PART_TYPE='HOLE';
      PARENT_PPT='HOLE';
      PARENT_PPT_PART='HOLE_TH-EMPTY,HOLE1247';
  end_body;
end_primitive;
primitive 'HOLE_TH-EMPTY,HOLE1248';
  pin
    '1':
      PIN_NUMBER='(1)';
      INPUT_LOAD='(-0.01,0.01)';
      OUTPUT_LOAD='(1.0,-1.0)';
      BIDIRECTIONAL='TRUE';
      PINUSE='BI';
  end_pin;
  body
      CLASS='IO';
      PART_NAME='HOLE';
      PHYS_DES_PREFIX='H';
      STANDARD='';
      LIFECYCLE='';
      JEDEC_TYPE='HOLE_C4-5D3-8B8I5-6_RO6-6_NPT_RB';
      DESCRIPTION='HOLE_C4-5D3-8B8I5-6_RO6-6_NPT_RB';
      COMPONENT_TYPE='';
      LEAD_LENGTH='';
      DFM_EXCLUSION='';
      PARENT_PART_TYPE='HOLE';
      PARENT_PPT='HOLE';
      PARENT_PPT_PART='HOLE_TH-EMPTY,HOLE1248';
  end_body;
end_primitive;
primitive 'HOLE_TH-EMPTY,HOLE620';
  pin
    '1':
      PIN_NUMBER='(1)';
      INPUT_LOAD='(-0.01,0.01)';
      OUTPUT_LOAD='(1.0,-1.0)';
      BIDIRECTIONAL='TRUE';
      PINUSE='BI';
  end_pin;
  body
      CLASS='IO';
      PART_NAME='HOLE';
      PHYS_DES_PREFIX='H';
      STANDARD='';
      LIFECYCLE='';
      JEDEC_TYPE='HOLE_C6D3-4B6_NPB';
      DESCRIPTION='HOLE_C6D3-4B6_NPB';
      COMPONENT_TYPE='';
      LEAD_LENGTH='';
      DFM_EXCLUSION='';
      PARENT_PART_TYPE='HOLE';
      PARENT_PPT='HOLE';
      PARENT_PPT_PART='HOLE_TH-EMPTY,HOLE620';
  end_body;
end_primitive;
primitive 'HOLE_TH-EMPTY,TMP-C_HOLE8';
  pin
    '1':
      PIN_NUMBER='(1)';
      INPUT_LOAD='(-0.01,0.01)';
      OUTPUT_LOAD='(1.0,-1.0)';
      BIDIRECTIONAL='TRUE';
      PINUSE='BI';
  end_pin;
  body
      CLASS='IO';
      PART_NAME='HOLE';
      PHYS_DES_PREFIX='H';
      STANDARD='';
      LIFECYCLE='';
      JEDEC_TYPE='HOLE_C6-5D3-2';
      DESCRIPTION='HOLE_C6-5D3-2';
      COMPONENT_TYPE='';
      LEAD_LENGTH='';
      DFM_EXCLUSION='';
      PARENT_PART_TYPE='HOLE';
      PARENT_PPT='HOLE';
      PARENT_PPT_PART='HOLE_TH-EMPTY,TMP-C_HOLE8';
  end_body;
end_primitive;
primitive 'IDTQS3VH257PAG_SMLF-IDTQS3VH25A';
  pin
    'YA':
      PIN_NUMBER='(4)';
      INPUT_LOAD='(-0.01,0.01)';
      OUTPUT_LOAD='(1.0,-1.0)';
      BIDIRECTIONAL='TRUE';
      PINUSE='BI';
    'YB':
      PIN_NUMBER='(7)';
      INPUT_LOAD='(-0.01,0.01)';
      OUTPUT_LOAD='(1.0,-1.0)';
      BIDIRECTIONAL='TRUE';
      PINUSE='BI';
    'YC':
      PIN_NUMBER='(9)';
      INPUT_LOAD='(-0.01,0.01)';
      OUTPUT_LOAD='(1.0,-1.0)';
      BIDIRECTIONAL='TRUE';
      PINUSE='BI';
    'YD':
      PIN_NUMBER='(12)';
      INPUT_LOAD='(-0.01,0.01)';
      OUTPUT_LOAD='(1.0,-1.0)';
      BIDIRECTIONAL='TRUE';
      PINUSE='BI';
    'S':
      PIN_NUMBER='(1)';
      INPUT_LOAD='(-0.01,0.01)';
      PINUSE='IN';
    'E*':
      PIN_NUMBER='(15)';
      INPUT_LOAD='(-0.01,0.01)';
      PINUSE='IN';
    'I_0A':
      PIN_NUMBER='(2)';
      INPUT_LOAD='(-0.01,0.01)';
      OUTPUT_LOAD='(1.0,-1.0)';
      BIDIRECTIONAL='TRUE';
      PINUSE='BI';
    'I_1A':
      PIN_NUMBER='(3)';
      INPUT_LOAD='(-0.01,0.01)';
      OUTPUT_LOAD='(1.0,-1.0)';
      BIDIRECTIONAL='TRUE';
      PINUSE='BI';
    'I_1B':
      PIN_NUMBER='(6)';
      INPUT_LOAD='(-0.01,0.01)';
      OUTPUT_LOAD='(1.0,-1.0)';
      BIDIRECTIONAL='TRUE';
      PINUSE='BI';
    'I_0B':
      PIN_NUMBER='(5)';
      INPUT_LOAD='(-0.01,0.01)';
      OUTPUT_LOAD='(1.0,-1.0)';
      BIDIRECTIONAL='TRUE';
      PINUSE='BI';
    'I_1C':
      PIN_NUMBER='(10)';
      INPUT_LOAD='(-0.01,0.01)';
      OUTPUT_LOAD='(1.0,-1.0)';
      BIDIRECTIONAL='TRUE';
      PINUSE='BI';
    'I_0C':
      PIN_NUMBER='(11)';
      INPUT_LOAD='(-0.01,0.01)';
      OUTPUT_LOAD='(1.0,-1.0)';
      BIDIRECTIONAL='TRUE';
      PINUSE='BI';
    'I_0D':
      PIN_NUMBER='(14)';
      INPUT_LOAD='(-0.01,0.01)';
      OUTPUT_LOAD='(1.0,-1.0)';
      BIDIRECTIONAL='TRUE';
      PINUSE='BI';
    'I_1D':
      PIN_NUMBER='(13)';
      INPUT_LOAD='(-0.01,0.01)';
      OUTPUT_LOAD='(1.0,-1.0)';
      BIDIRECTIONAL='TRUE';
      PINUSE='BI';
    'GND':
      PIN_NUMBER='(8)';
      PINUSE='POWER';
    'VCC':
      PIN_NUMBER='(16)';
      PINUSE='POWER';
  end_pin;
  body
      PHYS_DES_PREFIX='U';
      CLASS='IC';
      PART_NAME='IDTQS3VH257PAG';
      BODY_NAME='IDTQS3VH257PAG';
      STANDARD='';
      LIFECYCLE='';
      ENVCOMP='YES';
      JEDEC_TYPE='TSSOP16';
      DESCRIPTION='IC OTHER(16P)IDTQS3VH257PAG(TSSOP)';
      HEIGHT='.048IN';
      COMPONENT_TYPE='SMALLSMT';
      LEAD_LENGTH='';
      LPID='';
      DAY='20100709';
      PARENT_PART_TYPE='IDTQS3VH257PAG';
      PARENT_PPT='IDTQS3VH257PAG';
      PARENT_PPT_PART='IDTQS3VH257PAG_SMLF-IDTQS3VH257PAG,IDTQS3VH257PAG,IC,AL000257K00';
  end_body;
end_primitive;
primitive 'K4A8G165WCBCTD-K4A8G165WC-BCTDA';
  pin
    'A0':
      PIN_NUMBER='(P3)';
      INPUT_LOAD='(-0.01,0.01)';
      PINUSE='IN';
    'A1':
      PIN_NUMBER='(P7)';
      INPUT_LOAD='(-0.01,0.01)';
      PINUSE='IN';
    'A10||AP':
      PIN_NUMBER='(M3)';
      INPUT_LOAD='(-0.01,0.01)';
      PINUSE='IN';
    'A11':
      PIN_NUMBER='(T2)';
      INPUT_LOAD='(-0.01,0.01)';
      PINUSE='IN';
    'A12||BC_N':
      PIN_NUMBER='(M7)';
      INPUT_LOAD='(-0.01,0.01)';
      PINUSE='IN';
    'A13':
      PIN_NUMBER='(T8)';
      INPUT_LOAD='(-0.01,0.01)';
      PINUSE='IN';
    'A2':
      PIN_NUMBER='(R3)';
      INPUT_LOAD='(-0.01,0.01)';
      PINUSE='IN';
    'A3':
      PIN_NUMBER='(N7)';
      INPUT_LOAD='(-0.01,0.01)';
      PINUSE='IN';
    'A4':
      PIN_NUMBER='(N3)';
      INPUT_LOAD='(-0.01,0.01)';
      PINUSE='IN';
    'A5':
      PIN_NUMBER='(P8)';
      INPUT_LOAD='(-0.01,0.01)';
      PINUSE='IN';
    'A6':
      PIN_NUMBER='(P2)';
      INPUT_LOAD='(-0.01,0.01)';
      PINUSE='IN';
    'A7':
      PIN_NUMBER='(R8)';
      INPUT_LOAD='(-0.01,0.01)';
      PINUSE='IN';
    'A8':
      PIN_NUMBER='(R2)';
      INPUT_LOAD='(-0.01,0.01)';
      PINUSE='IN';
    'A9':
      PIN_NUMBER='(R7)';
      INPUT_LOAD='(-0.01,0.01)';
      PINUSE='IN';
    'ACT_N':
      PIN_NUMBER='(L3)';
      INPUT_LOAD='(-0.01,0.01)';
      PINUSE='IN';
    'ALERT_N':
      PIN_NUMBER='(P9)';
      BIDIRECTIONAL='TRUE';
      INPUT_LOAD='(-0.01,0.01)';
      OUTPUT_LOAD='(1.0,-1.0)';
      PINUSE='BI';
    'BA0':
      PIN_NUMBER='(N2)';
      INPUT_LOAD='(-0.01,0.01)';
      PINUSE='IN';
    'BA1':
      PIN_NUMBER='(N8)';
      INPUT_LOAD='(-0.01,0.01)';
      PINUSE='IN';
    'BG0':
      PIN_NUMBER='(M2)';
      INPUT_LOAD='(-0.01,0.01)';
      PINUSE='IN';
    'CAS_N||A15':
      PIN_NUMBER='(M8)';
      INPUT_LOAD='(-0.01,0.01)';
      PINUSE='IN';
    'CS_N':
      PIN_NUMBER='(L7)';
      INPUT_LOAD='(-0.01,0.01)';
      PINUSE='IN';
    'CKE':
      PIN_NUMBER='(K2)';
      INPUT_LOAD='(-0.01,0.01)';
      PINUSE='IN';
    'NC1':
      PIN_NUMBER='(T7)';
      OUTPUT_TYPE='(TS,TS)';
      INPUT_LOAD='(-0.01,0.01)';
      OUTPUT_LOAD='(1.0,-1.0)';
      PINUSE='TRI';
    'ODT':
      PIN_NUMBER='(K3)';
      INPUT_LOAD='(-0.01,0.01)';
      PINUSE='IN';
    'RAS_N':
      PIN_NUMBER='(L8)';
      INPUT_LOAD='(-0.01,0.01)';
      PINUSE='IN';
    'VDD0':
      PIN_NUMBER='(B3)';
      PINUSE='POWER';
      NO_LOAD_CHECK='Both';
      NO_IO_CHECK='Both';
      NO_ASSERT_CHECK='TRUE';
      NO_DIR_CHECK='TRUE';
      ALLOW_CONNECT='TRUE';
    'VDD1':
      PIN_NUMBER='(B9)';
      PINUSE='POWER';
      NO_LOAD_CHECK='Both';
      NO_IO_CHECK='Both';
      NO_ASSERT_CHECK='TRUE';
      NO_DIR_CHECK='TRUE';
      ALLOW_CONNECT='TRUE';
    'VDD2':
      PIN_NUMBER='(D1)';
      PINUSE='POWER';
      NO_LOAD_CHECK='Both';
      NO_IO_CHECK='Both';
      NO_ASSERT_CHECK='TRUE';
      NO_DIR_CHECK='TRUE';
      ALLOW_CONNECT='TRUE';
    'VDD3':
      PIN_NUMBER='(G7)';
      PINUSE='POWER';
      NO_LOAD_CHECK='Both';
      NO_IO_CHECK='Both';
      NO_ASSERT_CHECK='TRUE';
      NO_DIR_CHECK='TRUE';
      ALLOW_CONNECT='TRUE';
    'VDD4':
      PIN_NUMBER='(J1)';
      PINUSE='POWER';
      NO_LOAD_CHECK='Both';
      NO_IO_CHECK='Both';
      NO_ASSERT_CHECK='TRUE';
      NO_DIR_CHECK='TRUE';
      ALLOW_CONNECT='TRUE';
    'VDD5':
      PIN_NUMBER='(J9)';
      PINUSE='POWER';
      NO_LOAD_CHECK='Both';
      NO_IO_CHECK='Both';
      NO_ASSERT_CHECK='TRUE';
      NO_DIR_CHECK='TRUE';
      ALLOW_CONNECT='TRUE';
    'VDD6':
      PIN_NUMBER='(L1)';
      PINUSE='POWER';
      NO_LOAD_CHECK='Both';
      NO_IO_CHECK='Both';
      NO_ASSERT_CHECK='TRUE';
      NO_DIR_CHECK='TRUE';
      ALLOW_CONNECT='TRUE';
    'VDD7':
      PIN_NUMBER='(L9)';
      PINUSE='POWER';
      NO_LOAD_CHECK='Both';
      NO_IO_CHECK='Both';
      NO_ASSERT_CHECK='TRUE';
      NO_DIR_CHECK='TRUE';
      ALLOW_CONNECT='TRUE';
    'VDD8':
      PIN_NUMBER='(R1)';
      PINUSE='POWER';
      NO_LOAD_CHECK='Both';
      NO_IO_CHECK='Both';
      NO_ASSERT_CHECK='TRUE';
      NO_DIR_CHECK='TRUE';
      ALLOW_CONNECT='TRUE';
    'VDD9':
      PIN_NUMBER='(T9)';
      PINUSE='POWER';
      NO_LOAD_CHECK='Both';
      NO_IO_CHECK='Both';
      NO_ASSERT_CHECK='TRUE';
      NO_DIR_CHECK='TRUE';
      ALLOW_CONNECT='TRUE';
    'VDDQ0':
      PIN_NUMBER='(A1)';
      PINUSE='POWER';
      NO_LOAD_CHECK='Both';
      NO_IO_CHECK='Both';
      NO_ASSERT_CHECK='TRUE';
      NO_DIR_CHECK='TRUE';
      ALLOW_CONNECT='TRUE';
    'VDDQ1':
      PIN_NUMBER='(A9)';
      PINUSE='POWER';
      NO_LOAD_CHECK='Both';
      NO_IO_CHECK='Both';
      NO_ASSERT_CHECK='TRUE';
      NO_DIR_CHECK='TRUE';
      ALLOW_CONNECT='TRUE';
    'VDDQ2':
      PIN_NUMBER='(C1)';
      PINUSE='POWER';
      NO_LOAD_CHECK='Both';
      NO_IO_CHECK='Both';
      NO_ASSERT_CHECK='TRUE';
      NO_DIR_CHECK='TRUE';
      ALLOW_CONNECT='TRUE';
    'VDDQ3':
      PIN_NUMBER='(D9)';
      PINUSE='POWER';
      NO_LOAD_CHECK='Both';
      NO_IO_CHECK='Both';
      NO_ASSERT_CHECK='TRUE';
      NO_DIR_CHECK='TRUE';
      ALLOW_CONNECT='TRUE';
    'VDDQ4':
      PIN_NUMBER='(F2)';
      PINUSE='POWER';
      NO_LOAD_CHECK='Both';
      NO_IO_CHECK='Both';
      NO_ASSERT_CHECK='TRUE';
      NO_DIR_CHECK='TRUE';
      ALLOW_CONNECT='TRUE';
    'VDDQ5':
      PIN_NUMBER='(F8)';
      PINUSE='POWER';
      NO_LOAD_CHECK='Both';
      NO_IO_CHECK='Both';
      NO_ASSERT_CHECK='TRUE';
      NO_DIR_CHECK='TRUE';
      ALLOW_CONNECT='TRUE';
    'VDDQ6':
      PIN_NUMBER='(G1)';
      PINUSE='POWER';
      NO_LOAD_CHECK='Both';
      NO_IO_CHECK='Both';
      NO_ASSERT_CHECK='TRUE';
      NO_DIR_CHECK='TRUE';
      ALLOW_CONNECT='TRUE';
    'VDDQ7':
      PIN_NUMBER='(G9)';
      PINUSE='POWER';
      NO_LOAD_CHECK='Both';
      NO_IO_CHECK='Both';
      NO_ASSERT_CHECK='TRUE';
      NO_DIR_CHECK='TRUE';
      ALLOW_CONNECT='TRUE';
    'VDDQ8':
      PIN_NUMBER='(J2)';
      PINUSE='POWER';
      NO_LOAD_CHECK='Both';
      NO_IO_CHECK='Both';
      NO_ASSERT_CHECK='TRUE';
      NO_DIR_CHECK='TRUE';
      ALLOW_CONNECT='TRUE';
    'VDDQ9':
      PIN_NUMBER='(J8)';
      PINUSE='POWER';
      NO_LOAD_CHECK='Both';
      NO_IO_CHECK='Both';
      NO_ASSERT_CHECK='TRUE';
      NO_DIR_CHECK='TRUE';
      ALLOW_CONNECT='TRUE';
    'VPP0':
      PIN_NUMBER='(B1)';
      PINUSE='POWER';
      NO_LOAD_CHECK='Both';
      NO_IO_CHECK='Both';
      NO_ASSERT_CHECK='TRUE';
      NO_DIR_CHECK='TRUE';
      ALLOW_CONNECT='TRUE';
    'VPP1':
      PIN_NUMBER='(R9)';
      PINUSE='POWER';
      NO_LOAD_CHECK='Both';
      NO_IO_CHECK='Both';
      NO_ASSERT_CHECK='TRUE';
      NO_DIR_CHECK='TRUE';
      ALLOW_CONNECT='TRUE';
    'WE_N||A14':
      PIN_NUMBER='(L2)';
      INPUT_LOAD='(-0.01,0.01)';
      PINUSE='IN';
    'ZQ':
      PIN_NUMBER='(F9)';
      PINUSE='POWER';
      NO_LOAD_CHECK='Both';
      NO_IO_CHECK='Both';
      NO_ASSERT_CHECK='TRUE';
      NO_DIR_CHECK='TRUE';
      ALLOW_CONNECT='TRUE';
    'DQL0':
      PIN_NUMBER='(G2)';
      BIDIRECTIONAL='TRUE';
      INPUT_LOAD='(-0.01,0.01)';
      OUTPUT_LOAD='(1.0,-1.0)';
      PINUSE='BI';
    'DQL1':
      PIN_NUMBER='(F7)';
      BIDIRECTIONAL='TRUE';
      INPUT_LOAD='(-0.01,0.01)';
      OUTPUT_LOAD='(1.0,-1.0)';
      PINUSE='BI';
    'DQL2':
      PIN_NUMBER='(H3)';
      BIDIRECTIONAL='TRUE';
      INPUT_LOAD='(-0.01,0.01)';
      OUTPUT_LOAD='(1.0,-1.0)';
      PINUSE='BI';
    'DQL3':
      PIN_NUMBER='(H7)';
      BIDIRECTIONAL='TRUE';
      INPUT_LOAD='(-0.01,0.01)';
      OUTPUT_LOAD='(1.0,-1.0)';
      PINUSE='BI';
    'DQL4':
      PIN_NUMBER='(H2)';
      BIDIRECTIONAL='TRUE';
      INPUT_LOAD='(-0.01,0.01)';
      OUTPUT_LOAD='(1.0,-1.0)';
      PINUSE='BI';
    'DQL5':
      PIN_NUMBER='(H8)';
      BIDIRECTIONAL='TRUE';
      INPUT_LOAD='(-0.01,0.01)';
      OUTPUT_LOAD='(1.0,-1.0)';
      PINUSE='BI';
    'DQL6':
      PIN_NUMBER='(J3)';
      BIDIRECTIONAL='TRUE';
      INPUT_LOAD='(-0.01,0.01)';
      OUTPUT_LOAD='(1.0,-1.0)';
      PINUSE='BI';
    'DQL7':
      PIN_NUMBER='(J7)';
      BIDIRECTIONAL='TRUE';
      INPUT_LOAD='(-0.01,0.01)';
      OUTPUT_LOAD='(1.0,-1.0)';
      PINUSE='BI';
    'DQU0':
      PIN_NUMBER='(A3)';
      BIDIRECTIONAL='TRUE';
      INPUT_LOAD='(-0.01,0.01)';
      OUTPUT_LOAD='(1.0,-1.0)';
      PINUSE='BI';
    'DQU1':
      PIN_NUMBER='(B8)';
      BIDIRECTIONAL='TRUE';
      INPUT_LOAD='(-0.01,0.01)';
      OUTPUT_LOAD='(1.0,-1.0)';
      PINUSE='BI';
    'DQU2':
      PIN_NUMBER='(C3)';
      BIDIRECTIONAL='TRUE';
      INPUT_LOAD='(-0.01,0.01)';
      OUTPUT_LOAD='(1.0,-1.0)';
      PINUSE='BI';
    'DQU3':
      PIN_NUMBER='(C7)';
      BIDIRECTIONAL='TRUE';
      INPUT_LOAD='(-0.01,0.01)';
      OUTPUT_LOAD='(1.0,-1.0)';
      PINUSE='BI';
    'DQU4':
      PIN_NUMBER='(C2)';
      BIDIRECTIONAL='TRUE';
      INPUT_LOAD='(-0.01,0.01)';
      OUTPUT_LOAD='(1.0,-1.0)';
      PINUSE='BI';
    'DQU5':
      PIN_NUMBER='(C8)';
      BIDIRECTIONAL='TRUE';
      INPUT_LOAD='(-0.01,0.01)';
      OUTPUT_LOAD='(1.0,-1.0)';
      PINUSE='BI';
    'DQU6':
      PIN_NUMBER='(D3)';
      BIDIRECTIONAL='TRUE';
      INPUT_LOAD='(-0.01,0.01)';
      OUTPUT_LOAD='(1.0,-1.0)';
      PINUSE='BI';
    'DQU7':
      PIN_NUMBER='(D7)';
      BIDIRECTIONAL='TRUE';
      INPUT_LOAD='(-0.01,0.01)';
      OUTPUT_LOAD='(1.0,-1.0)';
      PINUSE='BI';
    'CK_T':
      PIN_NUMBER='(K7)';
      INPUT_LOAD='(-0.01,0.01)';
      PINUSE='IN';
    'CK_C':
      PIN_NUMBER='(K8)';
      INPUT_LOAD='(-0.01,0.01)';
      PINUSE='IN';
    'DQSU_T':
      PIN_NUMBER='(B7)';
      BIDIRECTIONAL='TRUE';
      INPUT_LOAD='(-0.01,0.01)';
      OUTPUT_LOAD='(1.0,-1.0)';
      PINUSE='BI';
    'DQSU_C':
      PIN_NUMBER='(A7)';
      BIDIRECTIONAL='TRUE';
      INPUT_LOAD='(-0.01,0.01)';
      OUTPUT_LOAD='(1.0,-1.0)';
      PINUSE='BI';
    'DQSL_T':
      PIN_NUMBER='(G3)';
      BIDIRECTIONAL='TRUE';
      INPUT_LOAD='(-0.01,0.01)';
      OUTPUT_LOAD='(1.0,-1.0)';
      PINUSE='BI';
    'DQSL_C':
      PIN_NUMBER='(F3)';
      BIDIRECTIONAL='TRUE';
      INPUT_LOAD='(-0.01,0.01)';
      OUTPUT_LOAD='(1.0,-1.0)';
      PINUSE='BI';
    'TEN':
      PIN_NUMBER='(N9)';
      INPUT_LOAD='(-0.01,0.01)';
      PINUSE='IN';
    'PAR':
      PIN_NUMBER='(T3)';
      INPUT_LOAD='(-0.01,0.01)';
      PINUSE='IN';
    'VREFCA':
      PIN_NUMBER='(M1)';
      PINUSE='POWER';
      NO_LOAD_CHECK='Both';
      NO_IO_CHECK='Both';
      NO_ASSERT_CHECK='TRUE';
      NO_DIR_CHECK='TRUE';
      ALLOW_CONNECT='TRUE';
    'VSS0':
      PIN_NUMBER='(B2)';
      PINUSE='POWER';
      NO_LOAD_CHECK='Both';
      NO_IO_CHECK='Both';
      NO_ASSERT_CHECK='TRUE';
      NO_DIR_CHECK='TRUE';
      ALLOW_CONNECT='TRUE';
    'VSS1':
      PIN_NUMBER='(E1)';
      PINUSE='POWER';
      NO_LOAD_CHECK='Both';
      NO_IO_CHECK='Both';
      NO_ASSERT_CHECK='TRUE';
      NO_DIR_CHECK='TRUE';
      ALLOW_CONNECT='TRUE';
    'VSS2':
      PIN_NUMBER='(E9)';
      PINUSE='POWER';
      NO_LOAD_CHECK='Both';
      NO_IO_CHECK='Both';
      NO_ASSERT_CHECK='TRUE';
      NO_DIR_CHECK='TRUE';
      ALLOW_CONNECT='TRUE';
    'VSS3':
      PIN_NUMBER='(G8)';
      PINUSE='POWER';
      NO_LOAD_CHECK='Both';
      NO_IO_CHECK='Both';
      NO_ASSERT_CHECK='TRUE';
      NO_DIR_CHECK='TRUE';
      ALLOW_CONNECT='TRUE';
    'VSS4':
      PIN_NUMBER='(K1)';
      PINUSE='POWER';
      NO_LOAD_CHECK='Both';
      NO_IO_CHECK='Both';
      NO_ASSERT_CHECK='TRUE';
      NO_DIR_CHECK='TRUE';
      ALLOW_CONNECT='TRUE';
    'VSS5':
      PIN_NUMBER='(K9)';
      PINUSE='POWER';
      NO_LOAD_CHECK='Both';
      NO_IO_CHECK='Both';
      NO_ASSERT_CHECK='TRUE';
      NO_DIR_CHECK='TRUE';
      ALLOW_CONNECT='TRUE';
    'VSS6':
      PIN_NUMBER='(M9)';
      PINUSE='POWER';
      NO_LOAD_CHECK='Both';
      NO_IO_CHECK='Both';
      NO_ASSERT_CHECK='TRUE';
      NO_DIR_CHECK='TRUE';
      ALLOW_CONNECT='TRUE';
    'VSS7':
      PIN_NUMBER='(N1)';
      PINUSE='POWER';
      NO_LOAD_CHECK='Both';
      NO_IO_CHECK='Both';
      NO_ASSERT_CHECK='TRUE';
      NO_DIR_CHECK='TRUE';
      ALLOW_CONNECT='TRUE';
    'VSS8':
      PIN_NUMBER='(T1)';
      PINUSE='POWER';
      NO_LOAD_CHECK='Both';
      NO_IO_CHECK='Both';
      NO_ASSERT_CHECK='TRUE';
      NO_DIR_CHECK='TRUE';
      ALLOW_CONNECT='TRUE';
    'VSSQ0':
      PIN_NUMBER='(A2)';
      PINUSE='POWER';
      NO_LOAD_CHECK='Both';
      NO_IO_CHECK='Both';
      NO_ASSERT_CHECK='TRUE';
      NO_DIR_CHECK='TRUE';
      ALLOW_CONNECT='TRUE';
    'VSSQ1':
      PIN_NUMBER='(A8)';
      PINUSE='POWER';
      NO_LOAD_CHECK='Both';
      NO_IO_CHECK='Both';
      NO_ASSERT_CHECK='TRUE';
      NO_DIR_CHECK='TRUE';
      ALLOW_CONNECT='TRUE';
    'VSSQ2':
      PIN_NUMBER='(C9)';
      PINUSE='POWER';
      NO_LOAD_CHECK='Both';
      NO_IO_CHECK='Both';
      NO_ASSERT_CHECK='TRUE';
      NO_DIR_CHECK='TRUE';
      ALLOW_CONNECT='TRUE';
    'VSSQ3':
      PIN_NUMBER='(D2)';
      PINUSE='POWER';
      NO_LOAD_CHECK='Both';
      NO_IO_CHECK='Both';
      NO_ASSERT_CHECK='TRUE';
      NO_DIR_CHECK='TRUE';
      ALLOW_CONNECT='TRUE';
    'VSSQ4':
      PIN_NUMBER='(D8)';
      PINUSE='POWER';
      NO_LOAD_CHECK='Both';
      NO_IO_CHECK='Both';
      NO_ASSERT_CHECK='TRUE';
      NO_DIR_CHECK='TRUE';
      ALLOW_CONNECT='TRUE';
    'VSSQ5':
      PIN_NUMBER='(E3)';
      PINUSE='POWER';
      NO_LOAD_CHECK='Both';
      NO_IO_CHECK='Both';
      NO_ASSERT_CHECK='TRUE';
      NO_DIR_CHECK='TRUE';
      ALLOW_CONNECT='TRUE';
    'VSSQ6':
      PIN_NUMBER='(E8)';
      PINUSE='POWER';
      NO_LOAD_CHECK='Both';
      NO_IO_CHECK='Both';
      NO_ASSERT_CHECK='TRUE';
      NO_DIR_CHECK='TRUE';
      ALLOW_CONNECT='TRUE';
    'VSSQ7':
      PIN_NUMBER='(F1)';
      PINUSE='POWER';
      NO_LOAD_CHECK='Both';
      NO_IO_CHECK='Both';
      NO_ASSERT_CHECK='TRUE';
      NO_DIR_CHECK='TRUE';
      ALLOW_CONNECT='TRUE';
    'VSSQ8':
      PIN_NUMBER='(H1)';
      PINUSE='POWER';
      NO_LOAD_CHECK='Both';
      NO_IO_CHECK='Both';
      NO_ASSERT_CHECK='TRUE';
      NO_DIR_CHECK='TRUE';
      ALLOW_CONNECT='TRUE';
    'VSSQ9':
      PIN_NUMBER='(H9)';
      PINUSE='POWER';
      NO_LOAD_CHECK='Both';
      NO_IO_CHECK='Both';
      NO_ASSERT_CHECK='TRUE';
      NO_DIR_CHECK='TRUE';
      ALLOW_CONNECT='TRUE';
    'DML_N||DBIL_N':
      PIN_NUMBER='(E7)';
      BIDIRECTIONAL='TRUE';
      INPUT_LOAD='(-0.01,0.01)';
      OUTPUT_LOAD='(1.0,-1.0)';
      PINUSE='BI';
    'DMU_N||DBIU_N':
      PIN_NUMBER='(E2)';
      BIDIRECTIONAL='TRUE';
      INPUT_LOAD='(-0.01,0.01)';
      OUTPUT_LOAD='(1.0,-1.0)';
      PINUSE='BI';
    'RESET_N':
      PIN_NUMBER='(P1)';
      INPUT_LOAD='(-0.01,0.01)';
      PINUSE='IN';
  end_pin;
  body
      PART_NAME='K4A8G165WCBCTD';
      BODY_NAME='K4A8G165WCBCTD';
      PHYS_DES_PREFIX='U';
      CLASS='IC';
      STANDARD='';
      LIFECYCLE='';
      JEDEC_TYPE='BGA96XB';
      DESCRIPTION='IC SDRAM(96P)K4A8G165WC-BCTD(FBGA)QBCON';
      MANUFTR='SAM';
      MANUF_PN='K4A8G165WC-BCTD';
      RD_CMPLS_LVL='EP(V1)';
      CMPLS_LVL='CG';
      FROM_PJ='STORM PEAK-ERIC';
      DIP_SMD='';
      DATA='SAM_K4A8G165WC-BCTD.pdf';
      EE_CHECK_LIST='';
      FP_ECN='';
      PSL='';
      CREATOR='';
      STATUS='';
      MSD='N/A';
      ESD_CDM='N/A';
      ESD_HBM='N/A';
      ESD_MM='N/A';
      PIN_LENGTH_SHORT_PIN='0 MILS';
      PIN_LENGTH_LONG_PIN='0 MILS';
      CREATEDAY='20180814';
      PARENT_PART_TYPE='K4A8G165WCBCTD';
      PARENT_PPT='K4A8G165WCBCTD';
      PARENT_PPT_PART='K4A8G165WCBCTD-K4A8G165WC-BCTD,SMLF,IC,AKD5FGUT502';
  end_body;
end_primitive;
primitive 'LCMXO3LF2100C5BG256C-LCMXO3LF-A';
  pin
    'VCCIO0_D5':
      PIN_NUMBER='(D5,0,0,0,0,0,0)';
      PINUSE='POWER';
      NO_LOAD_CHECK='Both';
      NO_IO_CHECK='Both';
      NO_ASSERT_CHECK='TRUE';
      NO_DIR_CHECK='TRUE';
      ALLOW_CONNECT='TRUE';
    'VCCIO0_D12':
      PIN_NUMBER='(D12,0,0,0,0,0,0)';
      PINUSE='POWER';
      NO_LOAD_CHECK='Both';
      NO_IO_CHECK='Both';
      NO_ASSERT_CHECK='TRUE';
      NO_DIR_CHECK='TRUE';
      ALLOW_CONNECT='TRUE';
    'VCCIO0_G8':
      PIN_NUMBER='(G8,0,0,0,0,0,0)';
      PINUSE='POWER';
      NO_LOAD_CHECK='Both';
      NO_IO_CHECK='Both';
      NO_ASSERT_CHECK='TRUE';
      NO_DIR_CHECK='TRUE';
      ALLOW_CONNECT='TRUE';
    'VCCIO0_G9':
      PIN_NUMBER='(G9,0,0,0,0,0,0)';
      PINUSE='POWER';
      NO_LOAD_CHECK='Both';
      NO_IO_CHECK='Both';
      NO_ASSERT_CHECK='TRUE';
      NO_DIR_CHECK='TRUE';
      ALLOW_CONNECT='TRUE';
    'PT9A':
      PIN_NUMBER='(C4,0,0,0,0,0,0)';
      BIDIRECTIONAL='TRUE';
      INPUT_LOAD='(-0.01,0.01)';
      OUTPUT_LOAD='(1.0,-1.0)';
      PINUSE='BI';
    'PT9B':
      PIN_NUMBER='(B5,0,0,0,0,0,0)';
      BIDIRECTIONAL='TRUE';
      INPUT_LOAD='(-0.01,0.01)';
      OUTPUT_LOAD='(1.0,-1.0)';
      PINUSE='BI';
    'PT9C':
      PIN_NUMBER='(B3,0,0,0,0,0,0)';
      BIDIRECTIONAL='TRUE';
      INPUT_LOAD='(-0.01,0.01)';
      OUTPUT_LOAD='(1.0,-1.0)';
      PINUSE='BI';
    'PT10A':
      PIN_NUMBER='(A4,0,0,0,0,0,0)';
      BIDIRECTIONAL='TRUE';
      INPUT_LOAD='(-0.01,0.01)';
      OUTPUT_LOAD='(1.0,-1.0)';
      PINUSE='BI';
    'PT10B':
      PIN_NUMBER='(C5,0,0,0,0,0,0)';
      BIDIRECTIONAL='TRUE';
      INPUT_LOAD='(-0.01,0.01)';
      OUTPUT_LOAD='(1.0,-1.0)';
      PINUSE='BI';
    'PT11A':
      PIN_NUMBER='(A5,0,0,0,0,0,0)';
      BIDIRECTIONAL='TRUE';
      INPUT_LOAD='(-0.01,0.01)';
      OUTPUT_LOAD='(1.0,-1.0)';
      PINUSE='BI';
    'PT11B':
      PIN_NUMBER='(B6,0,0,0,0,0,0)';
      BIDIRECTIONAL='TRUE';
      INPUT_LOAD='(-0.01,0.01)';
      OUTPUT_LOAD='(1.0,-1.0)';
      PINUSE='BI';
    'PT11C':
      PIN_NUMBER='(A3,0,0,0,0,0,0)';
      BIDIRECTIONAL='TRUE';
      INPUT_LOAD='(-0.01,0.01)';
      OUTPUT_LOAD='(1.0,-1.0)';
      PINUSE='BI';
    'PT11D':
      PIN_NUMBER='(B4,0,0,0,0,0,0)';
      BIDIRECTIONAL='TRUE';
      INPUT_LOAD='(-0.01,0.01)';
      OUTPUT_LOAD='(1.0,-1.0)';
      PINUSE='BI';
    'PT12A':
      PIN_NUMBER='(D6,0,0,0,0,0,0)';
      BIDIRECTIONAL='TRUE';
      INPUT_LOAD='(-0.01,0.01)';
      OUTPUT_LOAD='(1.0,-1.0)';
      PINUSE='BI';
    'PT12B':
      PIN_NUMBER='(E7,0,0,0,0,0,0)';
      BIDIRECTIONAL='TRUE';
      INPUT_LOAD='(-0.01,0.01)';
      OUTPUT_LOAD='(1.0,-1.0)';
      PINUSE='BI';
    'PT12C||TDO':
      PIN_NUMBER='(C6,0,0,0,0,0,0)';
      BIDIRECTIONAL='TRUE';
      INPUT_LOAD='(-0.01,0.01)';
      OUTPUT_LOAD='(1.0,-1.0)';
      PINUSE='BI';
    'PT12D||TDI':
      PIN_NUMBER='(A6,0,0,0,0,0,0)';
      BIDIRECTIONAL='TRUE';
      INPUT_LOAD='(-0.01,0.01)';
      OUTPUT_LOAD='(1.0,-1.0)';
      PINUSE='BI';
    'PT13A':
      PIN_NUMBER='(B7,0,0,0,0,0,0)';
      BIDIRECTIONAL='TRUE';
      INPUT_LOAD='(-0.01,0.01)';
      OUTPUT_LOAD='(1.0,-1.0)';
      PINUSE='BI';
    'PT13B':
      PIN_NUMBER='(C7,0,0,0,0,0,0)';
      BIDIRECTIONAL='TRUE';
      INPUT_LOAD='(-0.01,0.01)';
      OUTPUT_LOAD='(1.0,-1.0)';
      PINUSE='BI';
    'PT13C':
      PIN_NUMBER='(E6,0,0,0,0,0,0)';
      BIDIRECTIONAL='TRUE';
      INPUT_LOAD='(-0.01,0.01)';
      OUTPUT_LOAD='(1.0,-1.0)';
      PINUSE='BI';
    'PT13D':
      PIN_NUMBER='(D7,0,0,0,0,0,0)';
      BIDIRECTIONAL='TRUE';
      INPUT_LOAD='(-0.01,0.01)';
      OUTPUT_LOAD='(1.0,-1.0)';
      PINUSE='BI';
    'PT16A':
      PIN_NUMBER='(F7,0,0,0,0,0,0)';
      BIDIRECTIONAL='TRUE';
      INPUT_LOAD='(-0.01,0.01)';
      OUTPUT_LOAD='(1.0,-1.0)';
      PINUSE='BI';
    'PT16B':
      PIN_NUMBER='(E8,0,0,0,0,0,0)';
      BIDIRECTIONAL='TRUE';
      INPUT_LOAD='(-0.01,0.01)';
      OUTPUT_LOAD='(1.0,-1.0)';
      PINUSE='BI';
    'PT16C||TCK':
      PIN_NUMBER='(A7,0,0,0,0,0,0)';
      BIDIRECTIONAL='TRUE';
      INPUT_LOAD='(-0.01,0.01)';
      OUTPUT_LOAD='(1.0,-1.0)';
      PINUSE='BI';
    'PT16D||TMS':
      PIN_NUMBER='(B8,0,0,0,0,0,0)';
      BIDIRECTIONAL='TRUE';
      INPUT_LOAD='(-0.01,0.01)';
      OUTPUT_LOAD='(1.0,-1.0)';
      PINUSE='BI';
    'PT17A||PCLKT0_1':
      PIN_NUMBER='(C8,0,0,0,0,0,0)';
      BIDIRECTIONAL='TRUE';
      INPUT_LOAD='(-0.01,0.01)';
      OUTPUT_LOAD='(1.0,-1.0)';
      PINUSE='BI';
    'PT17B||PCLKC0_1':
      PIN_NUMBER='(A8,0,0,0,0,0,0)';
      BIDIRECTIONAL='TRUE';
      INPUT_LOAD='(-0.01,0.01)';
      OUTPUT_LOAD='(1.0,-1.0)';
      PINUSE='BI';
    'PT17C':
      PIN_NUMBER='(D8,0,0,0,0,0,0)';
      BIDIRECTIONAL='TRUE';
      INPUT_LOAD='(-0.01,0.01)';
      OUTPUT_LOAD='(1.0,-1.0)';
      PINUSE='BI';
    'PT17D':
      PIN_NUMBER='(E9,0,0,0,0,0,0)';
      BIDIRECTIONAL='TRUE';
      INPUT_LOAD='(-0.01,0.01)';
      OUTPUT_LOAD='(1.0,-1.0)';
      PINUSE='BI';
    'PT18B':
      PIN_NUMBER='(D9,0,0,0,0,0,0)';
      BIDIRECTIONAL='TRUE';
      INPUT_LOAD='(-0.01,0.01)';
      OUTPUT_LOAD='(1.0,-1.0)';
      PINUSE='BI';
    'PT18C||SCL||PCLKT0_0':
      PIN_NUMBER='(A9,0,0,0,0,0,0)';
      BIDIRECTIONAL='TRUE';
      INPUT_LOAD='(-0.01,0.01)';
      OUTPUT_LOAD='(1.0,-1.0)';
      PINUSE='BI';
    'PT18D||SDA||PCLKC0_0':
      PIN_NUMBER='(C9,0,0,0,0,0,0)';
      BIDIRECTIONAL='TRUE';
      INPUT_LOAD='(-0.01,0.01)';
      OUTPUT_LOAD='(1.0,-1.0)';
      PINUSE='BI';
    'PT19A':
      PIN_NUMBER='(B9,0,0,0,0,0,0)';
      BIDIRECTIONAL='TRUE';
      INPUT_LOAD='(-0.01,0.01)';
      OUTPUT_LOAD='(1.0,-1.0)';
      PINUSE='BI';
    'PT19B':
      PIN_NUMBER='(A10,0,0,0,0,0,0)';
      BIDIRECTIONAL='TRUE';
      INPUT_LOAD='(-0.01,0.01)';
      OUTPUT_LOAD='(1.0,-1.0)';
      PINUSE='BI';
    'PT19C':
      PIN_NUMBER='(F9,0,0,0,0,0,0)';
      BIDIRECTIONAL='TRUE';
      INPUT_LOAD='(-0.01,0.01)';
      OUTPUT_LOAD='(1.0,-1.0)';
      PINUSE='BI';
    'PT19D':
      PIN_NUMBER='(E11,0,0,0,0,0,0)';
      BIDIRECTIONAL='TRUE';
      INPUT_LOAD='(-0.01,0.01)';
      OUTPUT_LOAD='(1.0,-1.0)';
      PINUSE='BI';
    'PT20A':
      PIN_NUMBER='(D10,0,0,0,0,0,0)';
      BIDIRECTIONAL='TRUE';
      INPUT_LOAD='(-0.01,0.01)';
      OUTPUT_LOAD='(1.0,-1.0)';
      PINUSE='BI';
    'PT20B':
      PIN_NUMBER='(E10,0,0,0,0,0,0)';
      BIDIRECTIONAL='TRUE';
      INPUT_LOAD='(-0.01,0.01)';
      OUTPUT_LOAD='(1.0,-1.0)';
      PINUSE='BI';
    'PT20C||JTAGENB':
      PIN_NUMBER='(C10,0,0,0,0,0,0)';
      BIDIRECTIONAL='TRUE';
      INPUT_LOAD='(-0.01,0.01)';
      OUTPUT_LOAD='(1.0,-1.0)';
      PINUSE='BI';
    'PT20D||PROGRAMN':
      PIN_NUMBER='(B10,0,0,0,0,0,0)';
      BIDIRECTIONAL='TRUE';
      INPUT_LOAD='(-0.01,0.01)';
      OUTPUT_LOAD='(1.0,-1.0)';
      PINUSE='BI';
    'PT21A':
      PIN_NUMBER='(A11,0,0,0,0,0,0)';
      BIDIRECTIONAL='TRUE';
      INPUT_LOAD='(-0.01,0.01)';
      OUTPUT_LOAD='(1.0,-1.0)';
      PINUSE='BI';
    'PT21B':
      PIN_NUMBER='(C11,0,0,0,0,0,0)';
      BIDIRECTIONAL='TRUE';
      INPUT_LOAD='(-0.01,0.01)';
      OUTPUT_LOAD='(1.0,-1.0)';
      PINUSE='BI';
    'PT21C':
      PIN_NUMBER='(F10,0,0,0,0,0,0)';
      BIDIRECTIONAL='TRUE';
      INPUT_LOAD='(-0.01,0.01)';
      OUTPUT_LOAD='(1.0,-1.0)';
      PINUSE='BI';
    'PT21D':
      PIN_NUMBER='(D11,0,0,0,0,0,0)';
      BIDIRECTIONAL='TRUE';
      INPUT_LOAD='(-0.01,0.01)';
      OUTPUT_LOAD='(1.0,-1.0)';
      PINUSE='BI';
    'PT22A':
      PIN_NUMBER='(B11,0,0,0,0,0,0)';
      BIDIRECTIONAL='TRUE';
      INPUT_LOAD='(-0.01,0.01)';
      OUTPUT_LOAD='(1.0,-1.0)';
      PINUSE='BI';
    'PT22B':
      PIN_NUMBER='(A12,0,0,0,0,0,0)';
      BIDIRECTIONAL='TRUE';
      INPUT_LOAD='(-0.01,0.01)';
      OUTPUT_LOAD='(1.0,-1.0)';
      PINUSE='BI';
    'PT22C':
      PIN_NUMBER='(B13,0,0,0,0,0,0)';
      BIDIRECTIONAL='TRUE';
      INPUT_LOAD='(-0.01,0.01)';
      OUTPUT_LOAD='(1.0,-1.0)';
      PINUSE='BI';
    'PT22D':
      PIN_NUMBER='(A14,0,0,0,0,0,0)';
      BIDIRECTIONAL='TRUE';
      INPUT_LOAD='(-0.01,0.01)';
      OUTPUT_LOAD='(1.0,-1.0)';
      PINUSE='BI';
    'PT23A':
      PIN_NUMBER='(C12,0,0,0,0,0,0)';
      BIDIRECTIONAL='TRUE';
      INPUT_LOAD='(-0.01,0.01)';
      OUTPUT_LOAD='(1.0,-1.0)';
      PINUSE='BI';
    'PT23B':
      PIN_NUMBER='(B12,0,0,0,0,0,0)';
      BIDIRECTIONAL='TRUE';
      INPUT_LOAD='(-0.01,0.01)';
      OUTPUT_LOAD='(1.0,-1.0)';
      PINUSE='BI';
    'PT24A':
      PIN_NUMBER='(B14,0,0,0,0,0,0)';
      BIDIRECTIONAL='TRUE';
      INPUT_LOAD='(-0.01,0.01)';
      OUTPUT_LOAD='(1.0,-1.0)';
      PINUSE='BI';
    'PT24B':
      PIN_NUMBER='(A15,0,0,0,0,0,0)';
      BIDIRECTIONAL='TRUE';
      INPUT_LOAD='(-0.01,0.01)';
      OUTPUT_LOAD='(1.0,-1.0)';
      PINUSE='BI';
    'PT24C||INITN':
      PIN_NUMBER='(A13,0,0,0,0,0,0)';
      BIDIRECTIONAL='TRUE';
      INPUT_LOAD='(-0.01,0.01)';
      OUTPUT_LOAD='(1.0,-1.0)';
      PINUSE='BI';
    'PT24D||DONE':
      PIN_NUMBER='(C13,0,0,0,0,0,0)';
      BIDIRECTIONAL='TRUE';
      INPUT_LOAD='(-0.01,0.01)';
      OUTPUT_LOAD='(1.0,-1.0)';
      PINUSE='BI';
    'PT18A':
      PIN_NUMBER='(F8,0,0,0,0,0,0)';
      BIDIRECTIONAL='TRUE';
      INPUT_LOAD='(-0.01,0.01)';
      OUTPUT_LOAD='(1.0,-1.0)';
      PINUSE='BI';
    'PR10C':
      PIN_NUMBER='(0,J11,0,0,0,0,0)';
      BIDIRECTIONAL='TRUE';
      INPUT_LOAD='(-0.01,0.01)';
      OUTPUT_LOAD='(1.0,-1.0)';
      PINUSE='BI';
    'PR10D':
      PIN_NUMBER='(0,L12,0,0,0,0,0)';
      BIDIRECTIONAL='TRUE';
      INPUT_LOAD='(-0.01,0.01)';
      OUTPUT_LOAD='(1.0,-1.0)';
      PINUSE='BI';
    'PR6A':
      PIN_NUMBER='(0,G16,0,0,0,0,0)';
      BIDIRECTIONAL='TRUE';
      INPUT_LOAD='(-0.01,0.01)';
      OUTPUT_LOAD='(1.0,-1.0)';
      PINUSE='BI';
    'PR6B':
      PIN_NUMBER='(0,H15,0,0,0,0,0)';
      BIDIRECTIONAL='TRUE';
      INPUT_LOAD='(-0.01,0.01)';
      OUTPUT_LOAD='(1.0,-1.0)';
      PINUSE='BI';
    'PR12C':
      PIN_NUMBER='(0,K11,0,0,0,0,0)';
      BIDIRECTIONAL='TRUE';
      INPUT_LOAD='(-0.01,0.01)';
      OUTPUT_LOAD='(1.0,-1.0)';
      PINUSE='BI';
    'PR12D':
      PIN_NUMBER='(0,L13,0,0,0,0,0)';
      BIDIRECTIONAL='TRUE';
      INPUT_LOAD='(-0.01,0.01)';
      OUTPUT_LOAD='(1.0,-1.0)';
      PINUSE='BI';
    'PR7A||PCLKT1_0':
      PIN_NUMBER='(0,H14,0,0,0,0,0)';
      BIDIRECTIONAL='TRUE';
      INPUT_LOAD='(-0.01,0.01)';
      OUTPUT_LOAD='(1.0,-1.0)';
      PINUSE='BI';
    'PR7B||PCLKC1_0':
      PIN_NUMBER='(0,H16,0,0,0,0,0)';
      BIDIRECTIONAL='TRUE';
      INPUT_LOAD='(-0.01,0.01)';
      OUTPUT_LOAD='(1.0,-1.0)';
      PINUSE='BI';
    'PR13C':
      PIN_NUMBER='(0,N15,0,0,0,0,0)';
      BIDIRECTIONAL='TRUE';
      INPUT_LOAD='(-0.01,0.01)';
      OUTPUT_LOAD='(1.0,-1.0)';
      PINUSE='BI';
    'PR13D':
      PIN_NUMBER='(0,P16,0,0,0,0,0)';
      BIDIRECTIONAL='TRUE';
      INPUT_LOAD='(-0.01,0.01)';
      OUTPUT_LOAD='(1.0,-1.0)';
      PINUSE='BI';
    'PR14A':
      PIN_NUMBER='(0,N16,0,0,0,0,0)';
      BIDIRECTIONAL='TRUE';
      INPUT_LOAD='(-0.01,0.01)';
      OUTPUT_LOAD='(1.0,-1.0)';
      PINUSE='BI';
    'PR14B':
      PIN_NUMBER='(0,N14,0,0,0,0,0)';
      BIDIRECTIONAL='TRUE';
      INPUT_LOAD='(-0.01,0.01)';
      OUTPUT_LOAD='(1.0,-1.0)';
      PINUSE='BI';
    'PR14C':
      PIN_NUMBER='(0,P15,0,0,0,0,0)';
      BIDIRECTIONAL='TRUE';
      INPUT_LOAD='(-0.01,0.01)';
      OUTPUT_LOAD='(1.0,-1.0)';
      PINUSE='BI';
    'PR14D':
      PIN_NUMBER='(0,R16,0,0,0,0,0)';
      BIDIRECTIONAL='TRUE';
      INPUT_LOAD='(-0.01,0.01)';
      OUTPUT_LOAD='(1.0,-1.0)';
      PINUSE='BI';
    'PR13A':
      PIN_NUMBER='(0,M14,0,0,0,0,0)';
      BIDIRECTIONAL='TRUE';
      INPUT_LOAD='(-0.01,0.01)';
      OUTPUT_LOAD='(1.0,-1.0)';
      PINUSE='BI';
    'PR13B':
      PIN_NUMBER='(0,M15,0,0,0,0,0)';
      BIDIRECTIONAL='TRUE';
      INPUT_LOAD='(-0.01,0.01)';
      OUTPUT_LOAD='(1.0,-1.0)';
      PINUSE='BI';
    'PR12A':
      PIN_NUMBER='(0,L15,0,0,0,0,0)';
      BIDIRECTIONAL='TRUE';
      INPUT_LOAD='(-0.01,0.01)';
      OUTPUT_LOAD='(1.0,-1.0)';
      PINUSE='BI';
    'PR12B':
      PIN_NUMBER='(0,M16,0,0,0,0,0)';
      BIDIRECTIONAL='TRUE';
      INPUT_LOAD='(-0.01,0.01)';
      OUTPUT_LOAD='(1.0,-1.0)';
      PINUSE='BI';
    'PR11C':
      PIN_NUMBER='(0,K13,0,0,0,0,0)';
      BIDIRECTIONAL='TRUE';
      INPUT_LOAD='(-0.01,0.01)';
      OUTPUT_LOAD='(1.0,-1.0)';
      PINUSE='BI';
    'PR11D':
      PIN_NUMBER='(0,K12,0,0,0,0,0)';
      BIDIRECTIONAL='TRUE';
      INPUT_LOAD='(-0.01,0.01)';
      OUTPUT_LOAD='(1.0,-1.0)';
      PINUSE='BI';
    'PR11A':
      PIN_NUMBER='(0,L16,0,0,0,0,0)';
      BIDIRECTIONAL='TRUE';
      INPUT_LOAD='(-0.01,0.01)';
      OUTPUT_LOAD='(1.0,-1.0)';
      PINUSE='BI';
    'PR11B':
      PIN_NUMBER='(0,L14,0,0,0,0,0)';
      BIDIRECTIONAL='TRUE';
      INPUT_LOAD='(-0.01,0.01)';
      OUTPUT_LOAD='(1.0,-1.0)';
      PINUSE='BI';
    'PR10A':
      PIN_NUMBER='(0,K14,0,0,0,0,0)';
      BIDIRECTIONAL='TRUE';
      INPUT_LOAD='(-0.01,0.01)';
      OUTPUT_LOAD='(1.0,-1.0)';
      PINUSE='BI';
    'PR10B':
      PIN_NUMBER='(0,K15,0,0,0,0,0)';
      BIDIRECTIONAL='TRUE';
      INPUT_LOAD='(-0.01,0.01)';
      OUTPUT_LOAD='(1.0,-1.0)';
      PINUSE='BI';
    'PR9A':
      PIN_NUMBER='(0,J15,0,0,0,0,0)';
      BIDIRECTIONAL='TRUE';
      INPUT_LOAD='(-0.01,0.01)';
      OUTPUT_LOAD='(1.0,-1.0)';
      PINUSE='BI';
    'PR9B':
      PIN_NUMBER='(0,K16,0,0,0,0,0)';
      BIDIRECTIONAL='TRUE';
      INPUT_LOAD='(-0.01,0.01)';
      OUTPUT_LOAD='(1.0,-1.0)';
      PINUSE='BI';
    'PR1A':
      PIN_NUMBER='(0,D14,0,0,0,0,0)';
      BIDIRECTIONAL='TRUE';
      INPUT_LOAD='(-0.01,0.01)';
      OUTPUT_LOAD='(1.0,-1.0)';
      PINUSE='BI';
    'PR1B':
      PIN_NUMBER='(0,E15,0,0,0,0,0)';
      BIDIRECTIONAL='TRUE';
      INPUT_LOAD='(-0.01,0.01)';
      OUTPUT_LOAD='(1.0,-1.0)';
      PINUSE='BI';
    'PR1C':
      PIN_NUMBER='(0,C15,0,0,0,0,0)';
      BIDIRECTIONAL='TRUE';
      INPUT_LOAD='(-0.01,0.01)';
      OUTPUT_LOAD='(1.0,-1.0)';
      PINUSE='BI';
    'PR1D':
      PIN_NUMBER='(0,B16,0,0,0,0,0)';
      BIDIRECTIONAL='TRUE';
      INPUT_LOAD='(-0.01,0.01)';
      OUTPUT_LOAD='(1.0,-1.0)';
      PINUSE='BI';
    'PR2A':
      PIN_NUMBER='(0,D16,0,0,0,0,0)';
      BIDIRECTIONAL='TRUE';
      INPUT_LOAD='(-0.01,0.01)';
      OUTPUT_LOAD='(1.0,-1.0)';
      PINUSE='BI';
    'PR2B':
      PIN_NUMBER='(0,E14,0,0,0,0,0)';
      BIDIRECTIONAL='TRUE';
      INPUT_LOAD='(-0.01,0.01)';
      OUTPUT_LOAD='(1.0,-1.0)';
      PINUSE='BI';
    'PR2C':
      PIN_NUMBER='(0,C16,0,0,0,0,0)';
      BIDIRECTIONAL='TRUE';
      INPUT_LOAD='(-0.01,0.01)';
      OUTPUT_LOAD='(1.0,-1.0)';
      PINUSE='BI';
    'PR2D':
      PIN_NUMBER='(0,D15,0,0,0,0,0)';
      BIDIRECTIONAL='TRUE';
      INPUT_LOAD='(-0.01,0.01)';
      OUTPUT_LOAD='(1.0,-1.0)';
      PINUSE='BI';
    'PR3C':
      PIN_NUMBER='(0,F13,0,0,0,0,0)';
      BIDIRECTIONAL='TRUE';
      INPUT_LOAD='(-0.01,0.01)';
      OUTPUT_LOAD='(1.0,-1.0)';
      PINUSE='BI';
    'PR3D':
      PIN_NUMBER='(0,G12,0,0,0,0,0)';
      BIDIRECTIONAL='TRUE';
      INPUT_LOAD='(-0.01,0.01)';
      OUTPUT_LOAD='(1.0,-1.0)';
      PINUSE='BI';
    'PR4C':
      PIN_NUMBER='(0,F12,0,0,0,0,0)';
      BIDIRECTIONAL='TRUE';
      INPUT_LOAD='(-0.01,0.01)';
      OUTPUT_LOAD='(1.0,-1.0)';
      PINUSE='BI';
    'PR4D':
      PIN_NUMBER='(0,G13,0,0,0,0,0)';
      BIDIRECTIONAL='TRUE';
      INPUT_LOAD='(-0.01,0.01)';
      OUTPUT_LOAD='(1.0,-1.0)';
      PINUSE='BI';
    'PR3A':
      PIN_NUMBER='(0,E16,0,0,0,0,0)';
      BIDIRECTIONAL='TRUE';
      INPUT_LOAD='(-0.01,0.01)';
      OUTPUT_LOAD='(1.0,-1.0)';
      PINUSE='BI';
    'PR3B':
      PIN_NUMBER='(0,F15,0,0,0,0,0)';
      BIDIRECTIONAL='TRUE';
      INPUT_LOAD='(-0.01,0.01)';
      OUTPUT_LOAD='(1.0,-1.0)';
      PINUSE='BI';
    'PR5C':
      PIN_NUMBER='(0,G11,0,0,0,0,0)';
      BIDIRECTIONAL='TRUE';
      INPUT_LOAD='(-0.01,0.01)';
      OUTPUT_LOAD='(1.0,-1.0)';
      PINUSE='BI';
    'PR5D':
      PIN_NUMBER='(0,H12,0,0,0,0,0)';
      BIDIRECTIONAL='TRUE';
      INPUT_LOAD='(-0.01,0.01)';
      OUTPUT_LOAD='(1.0,-1.0)';
      PINUSE='BI';
    'PR4A':
      PIN_NUMBER='(0,F14,0,0,0,0,0)';
      BIDIRECTIONAL='TRUE';
      INPUT_LOAD='(-0.01,0.01)';
      OUTPUT_LOAD='(1.0,-1.0)';
      PINUSE='BI';
    'PR4B':
      PIN_NUMBER='(0,F16,0,0,0,0,0)';
      BIDIRECTIONAL='TRUE';
      INPUT_LOAD='(-0.01,0.01)';
      OUTPUT_LOAD='(1.0,-1.0)';
      PINUSE='BI';
    'PR6C':
      PIN_NUMBER='(0,H13,0,0,0,0,0)';
      BIDIRECTIONAL='TRUE';
      INPUT_LOAD='(-0.01,0.01)';
      OUTPUT_LOAD='(1.0,-1.0)';
      PINUSE='BI';
    'PR6D':
      PIN_NUMBER='(0,J12,0,0,0,0,0)';
      BIDIRECTIONAL='TRUE';
      INPUT_LOAD='(-0.01,0.01)';
      OUTPUT_LOAD='(1.0,-1.0)';
      PINUSE='BI';
    'PR7C':
      PIN_NUMBER='(0,J16,0,0,0,0,0)';
      BIDIRECTIONAL='TRUE';
      INPUT_LOAD='(-0.01,0.01)';
      OUTPUT_LOAD='(1.0,-1.0)';
      PINUSE='BI';
    'PR7D':
      PIN_NUMBER='(0,J14,0,0,0,0,0)';
      BIDIRECTIONAL='TRUE';
      INPUT_LOAD='(-0.01,0.01)';
      OUTPUT_LOAD='(1.0,-1.0)';
      PINUSE='BI';
    'PR9C':
      PIN_NUMBER='(0,H11,0,0,0,0,0)';
      BIDIRECTIONAL='TRUE';
      INPUT_LOAD='(-0.01,0.01)';
      OUTPUT_LOAD='(1.0,-1.0)';
      PINUSE='BI';
    'PR9D':
      PIN_NUMBER='(0,J13,0,0,0,0,0)';
      BIDIRECTIONAL='TRUE';
      INPUT_LOAD='(-0.01,0.01)';
      OUTPUT_LOAD='(1.0,-1.0)';
      PINUSE='BI';
    'PR5A':
      PIN_NUMBER='(0,G15,0,0,0,0,0)';
      BIDIRECTIONAL='TRUE';
      INPUT_LOAD='(-0.01,0.01)';
      OUTPUT_LOAD='(1.0,-1.0)';
      PINUSE='BI';
    'PR5B':
      PIN_NUMBER='(0,G14,0,0,0,0,0)';
      BIDIRECTIONAL='TRUE';
      INPUT_LOAD='(-0.01,0.01)';
      OUTPUT_LOAD='(1.0,-1.0)';
      PINUSE='BI';
    'VCCIO1_M13':
      PIN_NUMBER='(0,M13,0,0,0,0,0)';
      PINUSE='POWER';
      NO_LOAD_CHECK='Both';
      NO_IO_CHECK='Both';
      NO_ASSERT_CHECK='TRUE';
      NO_DIR_CHECK='TRUE';
      ALLOW_CONNECT='TRUE';
    'VCCIO1_J10':
      PIN_NUMBER='(0,J10,0,0,0,0,0)';
      PINUSE='POWER';
      NO_LOAD_CHECK='Both';
      NO_IO_CHECK='Both';
      NO_ASSERT_CHECK='TRUE';
      NO_DIR_CHECK='TRUE';
      ALLOW_CONNECT='TRUE';
    'VCCIO1_E13':
      PIN_NUMBER='(0,E13,0,0,0,0,0)';
      PINUSE='POWER';
      NO_LOAD_CHECK='Both';
      NO_IO_CHECK='Both';
      NO_ASSERT_CHECK='TRUE';
      NO_DIR_CHECK='TRUE';
      ALLOW_CONNECT='TRUE';
    'VCCIO1_H10':
      PIN_NUMBER='(0,H10,0,0,0,0,0)';
      PINUSE='POWER';
      NO_LOAD_CHECK='Both';
      NO_IO_CHECK='Both';
      NO_ASSERT_CHECK='TRUE';
      NO_DIR_CHECK='TRUE';
      ALLOW_CONNECT='TRUE';
    'PB9C':
      PIN_NUMBER='(0,0,M7,0,0,0,0)';
      BIDIRECTIONAL='TRUE';
      INPUT_LOAD='(-0.01,0.01)';
      OUTPUT_LOAD='(1.0,-1.0)';
      PINUSE='BI';
    'PB9D':
      PIN_NUMBER='(0,0,N7,0,0,0,0)';
      BIDIRECTIONAL='TRUE';
      INPUT_LOAD='(-0.01,0.01)';
      OUTPUT_LOAD='(1.0,-1.0)';
      PINUSE='BI';
    'PB11C':
      PIN_NUMBER='(0,0,M6,0,0,0,0)';
      BIDIRECTIONAL='TRUE';
      INPUT_LOAD='(-0.01,0.01)';
      OUTPUT_LOAD='(1.0,-1.0)';
      PINUSE='BI';
    'PB11D':
      PIN_NUMBER='(0,0,L8,0,0,0,0)';
      BIDIRECTIONAL='TRUE';
      INPUT_LOAD='(-0.01,0.01)';
      OUTPUT_LOAD='(1.0,-1.0)';
      PINUSE='BI';
    'PB11A||PCLKT2_0':
      PIN_NUMBER='(0,0,T7,0,0,0,0)';
      BIDIRECTIONAL='TRUE';
      INPUT_LOAD='(-0.01,0.01)';
      OUTPUT_LOAD='(1.0,-1.0)';
      PINUSE='BI';
    'PB11B||PCLKC2_0':
      PIN_NUMBER='(0,0,R8,0,0,0,0)';
      BIDIRECTIONAL='TRUE';
      INPUT_LOAD='(-0.01,0.01)';
      OUTPUT_LOAD='(1.0,-1.0)';
      PINUSE='BI';
    'PB12A':
      PIN_NUMBER='(0,0,P8,0,0,0,0)';
      BIDIRECTIONAL='TRUE';
      INPUT_LOAD='(-0.01,0.01)';
      OUTPUT_LOAD='(1.0,-1.0)';
      PINUSE='BI';
    'PB12B':
      PIN_NUMBER='(0,0,T8,0,0,0,0)';
      BIDIRECTIONAL='TRUE';
      INPUT_LOAD='(-0.01,0.01)';
      OUTPUT_LOAD='(1.0,-1.0)';
      PINUSE='BI';
    'PB12C':
      PIN_NUMBER='(0,0,N8,0,0,0,0)';
      BIDIRECTIONAL='TRUE';
      INPUT_LOAD='(-0.01,0.01)';
      OUTPUT_LOAD='(1.0,-1.0)';
      PINUSE='BI';
    'PB12D':
      PIN_NUMBER='(0,0,L9,0,0,0,0)';
      BIDIRECTIONAL='TRUE';
      INPUT_LOAD='(-0.01,0.01)';
      OUTPUT_LOAD='(1.0,-1.0)';
      PINUSE='BI';
    'PB16C':
      PIN_NUMBER='(0,0,M8,0,0,0,0)';
      BIDIRECTIONAL='TRUE';
      INPUT_LOAD='(-0.01,0.01)';
      OUTPUT_LOAD='(1.0,-1.0)';
      PINUSE='BI';
    'PB16D':
      PIN_NUMBER='(0,0,N9,0,0,0,0)';
      BIDIRECTIONAL='TRUE';
      INPUT_LOAD='(-0.01,0.01)';
      OUTPUT_LOAD='(1.0,-1.0)';
      PINUSE='BI';
    'PB16A||PCLKT2_1':
      PIN_NUMBER='(0,0,T9,0,0,0,0)';
      BIDIRECTIONAL='TRUE';
      INPUT_LOAD='(-0.01,0.01)';
      OUTPUT_LOAD='(1.0,-1.0)';
      PINUSE='BI';
    'PB16B||PCLKC2_1':
      PIN_NUMBER='(0,0,P9,0,0,0,0)';
      BIDIRECTIONAL='TRUE';
      INPUT_LOAD='(-0.01,0.01)';
      OUTPUT_LOAD='(1.0,-1.0)';
      PINUSE='BI';
    'PB18A':
      PIN_NUMBER='(0,0,R9,0,0,0,0)';
      BIDIRECTIONAL='TRUE';
      INPUT_LOAD='(-0.01,0.01)';
      OUTPUT_LOAD='(1.0,-1.0)';
      PINUSE='BI';
    'PB18B':
      PIN_NUMBER='(0,0,T10,0,0,0,0)';
      BIDIRECTIONAL='TRUE';
      INPUT_LOAD='(-0.01,0.01)';
      OUTPUT_LOAD='(1.0,-1.0)';
      PINUSE='BI';
    'PB18C':
      PIN_NUMBER='(0,0,M9,0,0,0,0)';
      BIDIRECTIONAL='TRUE';
      INPUT_LOAD='(-0.01,0.01)';
      OUTPUT_LOAD='(1.0,-1.0)';
      PINUSE='BI';
    'PB18D':
      PIN_NUMBER='(0,0,L10,0,0,0,0)';
      BIDIRECTIONAL='TRUE';
      INPUT_LOAD='(-0.01,0.01)';
      OUTPUT_LOAD='(1.0,-1.0)';
      PINUSE='BI';
    'PB19C':
      PIN_NUMBER='(0,0,N10,0,0,0,0)';
      BIDIRECTIONAL='TRUE';
      INPUT_LOAD='(-0.01,0.01)';
      OUTPUT_LOAD='(1.0,-1.0)';
      PINUSE='BI';
    'PB19D':
      PIN_NUMBER='(0,0,M11,0,0,0,0)';
      BIDIRECTIONAL='TRUE';
      INPUT_LOAD='(-0.01,0.01)';
      OUTPUT_LOAD='(1.0,-1.0)';
      PINUSE='BI';
    'PB19A':
      PIN_NUMBER='(0,0,P10,0,0,0,0)';
      BIDIRECTIONAL='TRUE';
      INPUT_LOAD='(-0.01,0.01)';
      OUTPUT_LOAD='(1.0,-1.0)';
      PINUSE='BI';
    'PB19B':
      PIN_NUMBER='(0,0,R10,0,0,0,0)';
      BIDIRECTIONAL='TRUE';
      INPUT_LOAD='(-0.01,0.01)';
      OUTPUT_LOAD='(1.0,-1.0)';
      PINUSE='BI';
    'PB21A':
      PIN_NUMBER='(0,0,T11,0,0,0,0)';
      BIDIRECTIONAL='TRUE';
      INPUT_LOAD='(-0.01,0.01)';
      OUTPUT_LOAD='(1.0,-1.0)';
      PINUSE='BI';
    'PB21B':
      PIN_NUMBER='(0,0,P11,0,0,0,0)';
      BIDIRECTIONAL='TRUE';
      INPUT_LOAD='(-0.01,0.01)';
      OUTPUT_LOAD='(1.0,-1.0)';
      PINUSE='BI';
    'PB21C':
      PIN_NUMBER='(0,0,M10,0,0,0,0)';
      BIDIRECTIONAL='TRUE';
      INPUT_LOAD='(-0.01,0.01)';
      OUTPUT_LOAD='(1.0,-1.0)';
      PINUSE='BI';
    'PB21D':
      PIN_NUMBER='(0,0,N11,0,0,0,0)';
      BIDIRECTIONAL='TRUE';
      INPUT_LOAD='(-0.01,0.01)';
      OUTPUT_LOAD='(1.0,-1.0)';
      PINUSE='BI';
    'PB22C':
      PIN_NUMBER='(0,0,R13,0,0,0,0)';
      BIDIRECTIONAL='TRUE';
      INPUT_LOAD='(-0.01,0.01)';
      OUTPUT_LOAD='(1.0,-1.0)';
      PINUSE='BI';
    'PB22D':
      PIN_NUMBER='(0,0,T14,0,0,0,0)';
      BIDIRECTIONAL='TRUE';
      INPUT_LOAD='(-0.01,0.01)';
      OUTPUT_LOAD='(1.0,-1.0)';
      PINUSE='BI';
    'PB22A':
      PIN_NUMBER='(0,0,R11,0,0,0,0)';
      BIDIRECTIONAL='TRUE';
      INPUT_LOAD='(-0.01,0.01)';
      OUTPUT_LOAD='(1.0,-1.0)';
      PINUSE='BI';
    'PB22B':
      PIN_NUMBER='(0,0,T12,0,0,0,0)';
      BIDIRECTIONAL='TRUE';
      INPUT_LOAD='(-0.01,0.01)';
      OUTPUT_LOAD='(1.0,-1.0)';
      PINUSE='BI';
    'PB24A':
      PIN_NUMBER='(0,0,P12,0,0,0,0)';
      BIDIRECTIONAL='TRUE';
      INPUT_LOAD='(-0.01,0.01)';
      OUTPUT_LOAD='(1.0,-1.0)';
      PINUSE='BI';
    'PB24B':
      PIN_NUMBER='(0,0,T13,0,0,0,0)';
      BIDIRECTIONAL='TRUE';
      INPUT_LOAD='(-0.01,0.01)';
      OUTPUT_LOAD='(1.0,-1.0)';
      PINUSE='BI';
    'PB25A||SN':
      PIN_NUMBER='(0,0,R12,0,0,0,0)';
      BIDIRECTIONAL='TRUE';
      INPUT_LOAD='(-0.01,0.01)';
      OUTPUT_LOAD='(1.0,-1.0)';
      PINUSE='BI';
    'PB25B||SI||SISPI':
      PIN_NUMBER='(0,0,P13,0,0,0,0)';
      BIDIRECTIONAL='TRUE';
      INPUT_LOAD='(-0.01,0.01)';
      OUTPUT_LOAD='(1.0,-1.0)';
      PINUSE='BI';
    'PB25C':
      PIN_NUMBER='(0,0,T15,0,0,0,0)';
      BIDIRECTIONAL='TRUE';
      INPUT_LOAD='(-0.01,0.01)';
      OUTPUT_LOAD='(1.0,-1.0)';
      PINUSE='BI';
    'PB25D':
      PIN_NUMBER='(0,0,R14,0,0,0,0)';
      BIDIRECTIONAL='TRUE';
      INPUT_LOAD='(-0.01,0.01)';
      OUTPUT_LOAD='(1.0,-1.0)';
      PINUSE='BI';
    'PB3A':
      PIN_NUMBER='(0,0,P4,0,0,0,0)';
      BIDIRECTIONAL='TRUE';
      INPUT_LOAD='(-0.01,0.01)';
      OUTPUT_LOAD='(1.0,-1.0)';
      PINUSE='BI';
    'PB3B':
      PIN_NUMBER='(0,0,T4,0,0,0,0)';
      BIDIRECTIONAL='TRUE';
      INPUT_LOAD='(-0.01,0.01)';
      OUTPUT_LOAD='(1.0,-1.0)';
      PINUSE='BI';
    'PB3C':
      PIN_NUMBER='(0,0,T2,0,0,0,0)';
      BIDIRECTIONAL='TRUE';
      INPUT_LOAD='(-0.01,0.01)';
      OUTPUT_LOAD='(1.0,-1.0)';
      PINUSE='BI';
    'PB3D':
      PIN_NUMBER='(0,0,R3,0,0,0,0)';
      BIDIRECTIONAL='TRUE';
      INPUT_LOAD='(-0.01,0.01)';
      OUTPUT_LOAD='(1.0,-1.0)';
      PINUSE='BI';
    'PB5A||CSSPIN':
      PIN_NUMBER='(0,0,R5,0,0,0,0)';
      BIDIRECTIONAL='TRUE';
      INPUT_LOAD='(-0.01,0.01)';
      OUTPUT_LOAD='(1.0,-1.0)';
      PINUSE='BI';
    'PB5B':
      PIN_NUMBER='(0,0,P5,0,0,0,0)';
      BIDIRECTIONAL='TRUE';
      INPUT_LOAD='(-0.01,0.01)';
      OUTPUT_LOAD='(1.0,-1.0)';
      PINUSE='BI';
    'PB6C':
      PIN_NUMBER='(0,0,T3,0,0,0,0)';
      BIDIRECTIONAL='TRUE';
      INPUT_LOAD='(-0.01,0.01)';
      OUTPUT_LOAD='(1.0,-1.0)';
      PINUSE='BI';
    'PB6D':
      PIN_NUMBER='(0,0,R4,0,0,0,0)';
      BIDIRECTIONAL='TRUE';
      INPUT_LOAD='(-0.01,0.01)';
      OUTPUT_LOAD='(1.0,-1.0)';
      PINUSE='BI';
    'PB6A':
      PIN_NUMBER='(0,0,T5,0,0,0,0)';
      BIDIRECTIONAL='TRUE';
      INPUT_LOAD='(-0.01,0.01)';
      OUTPUT_LOAD='(1.0,-1.0)';
      PINUSE='BI';
    'PB6B':
      PIN_NUMBER='(0,0,R6,0,0,0,0)';
      BIDIRECTIONAL='TRUE';
      INPUT_LOAD='(-0.01,0.01)';
      OUTPUT_LOAD='(1.0,-1.0)';
      PINUSE='BI';
    'PB8C':
      PIN_NUMBER='(0,0,N6,0,0,0,0)';
      BIDIRECTIONAL='TRUE';
      INPUT_LOAD='(-0.01,0.01)';
      OUTPUT_LOAD='(1.0,-1.0)';
      PINUSE='BI';
    'PB8D':
      PIN_NUMBER='(0,0,L7,0,0,0,0)';
      BIDIRECTIONAL='TRUE';
      INPUT_LOAD='(-0.01,0.01)';
      OUTPUT_LOAD='(1.0,-1.0)';
      PINUSE='BI';
    'PB8A||MCLK||CCLK':
      PIN_NUMBER='(0,0,P6,0,0,0,0)';
      BIDIRECTIONAL='TRUE';
      INPUT_LOAD='(-0.01,0.01)';
      OUTPUT_LOAD='(1.0,-1.0)';
      PINUSE='BI';
    'PB8B||SO||SPISO':
      PIN_NUMBER='(0,0,T6,0,0,0,0)';
      BIDIRECTIONAL='TRUE';
      INPUT_LOAD='(-0.01,0.01)';
      OUTPUT_LOAD='(1.0,-1.0)';
      PINUSE='BI';
    'PB9A':
      PIN_NUMBER='(0,0,R7,0,0,0,0)';
      BIDIRECTIONAL='TRUE';
      INPUT_LOAD='(-0.01,0.01)';
      OUTPUT_LOAD='(1.0,-1.0)';
      PINUSE='BI';
    'PB9B':
      PIN_NUMBER='(0,0,P7,0,0,0,0)';
      BIDIRECTIONAL='TRUE';
      INPUT_LOAD='(-0.01,0.01)';
      OUTPUT_LOAD='(1.0,-1.0)';
      PINUSE='BI';
    'VCCIO2_K8':
      PIN_NUMBER='(0,0,K8,0,0,0,0)';
      PINUSE='POWER';
      NO_LOAD_CHECK='Both';
      NO_IO_CHECK='Both';
      NO_ASSERT_CHECK='TRUE';
      NO_DIR_CHECK='TRUE';
      ALLOW_CONNECT='TRUE';
    'VCCIO2_K9':
      PIN_NUMBER='(0,0,K9,0,0,0,0)';
      PINUSE='POWER';
      NO_LOAD_CHECK='Both';
      NO_IO_CHECK='Both';
      NO_ASSERT_CHECK='TRUE';
      NO_DIR_CHECK='TRUE';
      ALLOW_CONNECT='TRUE';
    'VCCIO2_N12':
      PIN_NUMBER='(0,0,N12,0,0,0,0)';
      PINUSE='POWER';
      NO_LOAD_CHECK='Both';
      NO_IO_CHECK='Both';
      NO_ASSERT_CHECK='TRUE';
      NO_DIR_CHECK='TRUE';
      ALLOW_CONNECT='TRUE';
    'VCCIO2_N5':
      PIN_NUMBER='(0,0,N5,0,0,0,0)';
      PINUSE='POWER';
      NO_LOAD_CHECK='Both';
      NO_IO_CHECK='Both';
      NO_ASSERT_CHECK='TRUE';
      NO_DIR_CHECK='TRUE';
      ALLOW_CONNECT='TRUE';
    'PL11A':
      PIN_NUMBER='(0,0,0,L1,0,0,0)';
      BIDIRECTIONAL='TRUE';
      INPUT_LOAD='(-0.01,0.01)';
      OUTPUT_LOAD='(1.0,-1.0)';
      PINUSE='BI';
    'PL11B':
      PIN_NUMBER='(0,0,0,L3,0,0,0)';
      BIDIRECTIONAL='TRUE';
      INPUT_LOAD='(-0.01,0.01)';
      OUTPUT_LOAD='(1.0,-1.0)';
      PINUSE='BI';
    'PL11C':
      PIN_NUMBER='(0,0,0,K4,0,0,0)';
      BIDIRECTIONAL='TRUE';
      INPUT_LOAD='(-0.01,0.01)';
      OUTPUT_LOAD='(1.0,-1.0)';
      PINUSE='BI';
    'PL11D':
      PIN_NUMBER='(0,0,0,L5,0,0,0)';
      BIDIRECTIONAL='TRUE';
      INPUT_LOAD='(-0.01,0.01)';
      OUTPUT_LOAD='(1.0,-1.0)';
      PINUSE='BI';
    'PL12C':
      PIN_NUMBER='(0,0,0,K5,0,0,0)';
      BIDIRECTIONAL='TRUE';
      INPUT_LOAD='(-0.01,0.01)';
      OUTPUT_LOAD='(1.0,-1.0)';
      PINUSE='BI';
    'PL12D':
      PIN_NUMBER='(0,0,0,L4,0,0,0)';
      BIDIRECTIONAL='TRUE';
      INPUT_LOAD='(-0.01,0.01)';
      OUTPUT_LOAD='(1.0,-1.0)';
      PINUSE='BI';
    'PL12A||PCLKT3_0':
      PIN_NUMBER='(0,0,0,L2,0,0,0)';
      BIDIRECTIONAL='TRUE';
      INPUT_LOAD='(-0.01,0.01)';
      OUTPUT_LOAD='(1.0,-1.0)';
      PINUSE='BI';
    'PL12B||PCLKC3_0':
      PIN_NUMBER='(0,0,0,M1,0,0,0)';
      BIDIRECTIONAL='TRUE';
      INPUT_LOAD='(-0.01,0.01)';
      OUTPUT_LOAD='(1.0,-1.0)';
      PINUSE='BI';
    'PL14A':
      PIN_NUMBER='(0,0,0,M2,0,0,0)';
      BIDIRECTIONAL='TRUE';
      INPUT_LOAD='(-0.01,0.01)';
      OUTPUT_LOAD='(1.0,-1.0)';
      PINUSE='BI';
    'PL14B':
      PIN_NUMBER='(0,0,0,N3,0,0,0)';
      BIDIRECTIONAL='TRUE';
      INPUT_LOAD='(-0.01,0.01)';
      OUTPUT_LOAD='(1.0,-1.0)';
      PINUSE='BI';
    'PL14C':
      PIN_NUMBER='(0,0,0,R1,0,0,0)';
      BIDIRECTIONAL='TRUE';
      INPUT_LOAD='(-0.01,0.01)';
      OUTPUT_LOAD='(1.0,-1.0)';
      PINUSE='BI';
    'PL14D':
      PIN_NUMBER='(0,0,0,P2,0,0,0)';
      BIDIRECTIONAL='TRUE';
      INPUT_LOAD='(-0.01,0.01)';
      OUTPUT_LOAD='(1.0,-1.0)';
      PINUSE='BI';
    'VCCIO3':
      PIN_NUMBER='(0,0,0,M4,0,0,0)';
      PINUSE='POWER';
      NO_LOAD_CHECK='Both';
      NO_IO_CHECK='Both';
      NO_ASSERT_CHECK='TRUE';
      NO_DIR_CHECK='TRUE';
      ALLOW_CONNECT='TRUE';
    'PL13C':
      PIN_NUMBER='(0,0,0,N2,0,0,0)';
      BIDIRECTIONAL='TRUE';
      INPUT_LOAD='(-0.01,0.01)';
      OUTPUT_LOAD='(1.0,-1.0)';
      PINUSE='BI';
    'PL13D':
      PIN_NUMBER='(0,0,0,P1,0,0,0)';
      BIDIRECTIONAL='TRUE';
      INPUT_LOAD='(-0.01,0.01)';
      OUTPUT_LOAD='(1.0,-1.0)';
      PINUSE='BI';
    'PL13A':
      PIN_NUMBER='(0,0,0,M3,0,0,0)';
      BIDIRECTIONAL='TRUE';
      INPUT_LOAD='(-0.01,0.01)';
      OUTPUT_LOAD='(1.0,-1.0)';
      PINUSE='BI';
    'PL13B':
      PIN_NUMBER='(0,0,0,N1,0,0,0)';
      BIDIRECTIONAL='TRUE';
      INPUT_LOAD='(-0.01,0.01)';
      OUTPUT_LOAD='(1.0,-1.0)';
      PINUSE='BI';
    'PL6A':
      PIN_NUMBER='(0,0,0,0,G1,0,0)';
      BIDIRECTIONAL='TRUE';
      INPUT_LOAD='(-0.01,0.01)';
      OUTPUT_LOAD='(1.0,-1.0)';
      PINUSE='BI';
    'PL6B':
      PIN_NUMBER='(0,0,0,0,H2,0,0)';
      BIDIRECTIONAL='TRUE';
      INPUT_LOAD='(-0.01,0.01)';
      OUTPUT_LOAD='(1.0,-1.0)';
      PINUSE='BI';
    'PL6C':
      PIN_NUMBER='(0,0,0,0,H4,0,0)';
      BIDIRECTIONAL='TRUE';
      INPUT_LOAD='(-0.01,0.01)';
      OUTPUT_LOAD='(1.0,-1.0)';
      PINUSE='BI';
    'PL6D':
      PIN_NUMBER='(0,0,0,0,J6,0,0)';
      BIDIRECTIONAL='TRUE';
      INPUT_LOAD='(-0.01,0.01)';
      OUTPUT_LOAD='(1.0,-1.0)';
      PINUSE='BI';
    'PL7A':
      PIN_NUMBER='(0,0,0,0,H3,0,0)';
      BIDIRECTIONAL='TRUE';
      INPUT_LOAD='(-0.01,0.01)';
      OUTPUT_LOAD='(1.0,-1.0)';
      PINUSE='BI';
    'PL7B':
      PIN_NUMBER='(0,0,0,0,H1,0,0)';
      BIDIRECTIONAL='TRUE';
      INPUT_LOAD='(-0.01,0.01)';
      OUTPUT_LOAD='(1.0,-1.0)';
      PINUSE='BI';
    'PL7C||PCLKT4_0':
      PIN_NUMBER='(0,0,0,0,J1,0,0)';
      BIDIRECTIONAL='TRUE';
      INPUT_LOAD='(-0.01,0.01)';
      OUTPUT_LOAD='(1.0,-1.0)';
      PINUSE='BI';
    'PL7D||PCLKC4_0':
      PIN_NUMBER='(0,0,0,0,J3,0,0)';
      BIDIRECTIONAL='TRUE';
      INPUT_LOAD='(-0.01,0.01)';
      OUTPUT_LOAD='(1.0,-1.0)';
      PINUSE='BI';
    'PL10C':
      PIN_NUMBER='(0,0,0,0,J5,0,0)';
      BIDIRECTIONAL='TRUE';
      INPUT_LOAD='(-0.01,0.01)';
      OUTPUT_LOAD='(1.0,-1.0)';
      PINUSE='BI';
    'PL10D':
      PIN_NUMBER='(0,0,0,0,K6,0,0)';
      BIDIRECTIONAL='TRUE';
      INPUT_LOAD='(-0.01,0.01)';
      OUTPUT_LOAD='(1.0,-1.0)';
      PINUSE='BI';
    'PL10A':
      PIN_NUMBER='(0,0,0,0,K3,0,0)';
      BIDIRECTIONAL='TRUE';
      INPUT_LOAD='(-0.01,0.01)';
      OUTPUT_LOAD='(1.0,-1.0)';
      PINUSE='BI';
    'PL10B':
      PIN_NUMBER='(0,0,0,0,K2,0,0)';
      BIDIRECTIONAL='TRUE';
      INPUT_LOAD='(-0.01,0.01)';
      OUTPUT_LOAD='(1.0,-1.0)';
      PINUSE='BI';
    'PL9A':
      PIN_NUMBER='(0,0,0,0,J2,0,0)';
      BIDIRECTIONAL='TRUE';
      INPUT_LOAD='(-0.01,0.01)';
      OUTPUT_LOAD='(1.0,-1.0)';
      PINUSE='BI';
    'PL9B':
      PIN_NUMBER='(0,0,0,0,K1,0,0)';
      BIDIRECTIONAL='TRUE';
      INPUT_LOAD='(-0.01,0.01)';
      OUTPUT_LOAD='(1.0,-1.0)';
      PINUSE='BI';
    'PL9C':
      PIN_NUMBER='(0,0,0,0,H5,0,0)';
      BIDIRECTIONAL='TRUE';
      INPUT_LOAD='(-0.01,0.01)';
      OUTPUT_LOAD='(1.0,-1.0)';
      PINUSE='BI';
    'PL9D':
      PIN_NUMBER='(0,0,0,0,J4,0,0)';
      BIDIRECTIONAL='TRUE';
      INPUT_LOAD='(-0.01,0.01)';
      OUTPUT_LOAD='(1.0,-1.0)';
      PINUSE='BI';
    'VCCIO4_H7':
      PIN_NUMBER='(0,0,0,0,H7,0,0)';
      PINUSE='POWER';
      NO_LOAD_CHECK='Both';
      NO_IO_CHECK='Both';
      NO_ASSERT_CHECK='TRUE';
      NO_DIR_CHECK='TRUE';
      ALLOW_CONNECT='TRUE';
    'VCCIO4_J7':
      PIN_NUMBER='(0,0,0,0,J7,0,0)';
      PINUSE='POWER';
      NO_LOAD_CHECK='Both';
      NO_IO_CHECK='Both';
      NO_ASSERT_CHECK='TRUE';
      NO_DIR_CHECK='TRUE';
      ALLOW_CONNECT='TRUE';
    'PL1C':
      PIN_NUMBER='(0,0,0,0,0,B1,0)';
      BIDIRECTIONAL='TRUE';
      INPUT_LOAD='(-0.01,0.01)';
      OUTPUT_LOAD='(1.0,-1.0)';
      PINUSE='BI';
    'PL1D':
      PIN_NUMBER='(0,0,0,0,0,C2,0)';
      BIDIRECTIONAL='TRUE';
      INPUT_LOAD='(-0.01,0.01)';
      OUTPUT_LOAD='(1.0,-1.0)';
      PINUSE='BI';
    'PL1A||L_GPLLT_FB':
      PIN_NUMBER='(0,0,0,0,0,D3,0)';
      BIDIRECTIONAL='TRUE';
      INPUT_LOAD='(-0.01,0.01)';
      OUTPUT_LOAD='(1.0,-1.0)';
      PINUSE='BI';
    'PL1B||L_GPLLC_FB':
      PIN_NUMBER='(0,0,0,0,0,D1,0)';
      BIDIRECTIONAL='TRUE';
      INPUT_LOAD='(-0.01,0.01)';
      OUTPUT_LOAD='(1.0,-1.0)';
      PINUSE='BI';
    'PL2A||L_GPLLT_IN':
      PIN_NUMBER='(0,0,0,0,0,E2,0)';
      BIDIRECTIONAL='TRUE';
      INPUT_LOAD='(-0.01,0.01)';
      OUTPUT_LOAD='(1.0,-1.0)';
      PINUSE='BI';
    'PL2B||L_GPLLC_IN':
      PIN_NUMBER='(0,0,0,0,0,E3,0)';
      BIDIRECTIONAL='TRUE';
      INPUT_LOAD='(-0.01,0.01)';
      OUTPUT_LOAD='(1.0,-1.0)';
      PINUSE='BI';
    'PL2C':
      PIN_NUMBER='(0,0,0,0,0,C1,0)';
      BIDIRECTIONAL='TRUE';
      INPUT_LOAD='(-0.01,0.01)';
      OUTPUT_LOAD='(1.0,-1.0)';
      PINUSE='BI';
    'PL2D':
      PIN_NUMBER='(0,0,0,0,0,D2,0)';
      BIDIRECTIONAL='TRUE';
      INPUT_LOAD='(-0.01,0.01)';
      OUTPUT_LOAD='(1.0,-1.0)';
      PINUSE='BI';
    'PL3A||PCLKT5_0':
      PIN_NUMBER='(0,0,0,0,0,E1,0)';
      BIDIRECTIONAL='TRUE';
      INPUT_LOAD='(-0.01,0.01)';
      OUTPUT_LOAD='(1.0,-1.0)';
      PINUSE='BI';
    'PL3B||PCLKC5_0':
      PIN_NUMBER='(0,0,0,0,0,F2,0)';
      BIDIRECTIONAL='TRUE';
      INPUT_LOAD='(-0.01,0.01)';
      OUTPUT_LOAD='(1.0,-1.0)';
      PINUSE='BI';
    'PL3C':
      PIN_NUMBER='(0,0,0,0,0,F4,0)';
      BIDIRECTIONAL='TRUE';
      INPUT_LOAD='(-0.01,0.01)';
      OUTPUT_LOAD='(1.0,-1.0)';
      PINUSE='BI';
    'PL3D':
      PIN_NUMBER='(0,0,0,0,0,G6,0)';
      BIDIRECTIONAL='TRUE';
      INPUT_LOAD='(-0.01,0.01)';
      OUTPUT_LOAD='(1.0,-1.0)';
      PINUSE='BI';
    'PL5A':
      PIN_NUMBER='(0,0,0,0,0,G2,0)';
      BIDIRECTIONAL='TRUE';
      INPUT_LOAD='(-0.01,0.01)';
      OUTPUT_LOAD='(1.0,-1.0)';
      PINUSE='BI';
    'PL5B':
      PIN_NUMBER='(0,0,0,0,0,G3,0)';
      BIDIRECTIONAL='TRUE';
      INPUT_LOAD='(-0.01,0.01)';
      OUTPUT_LOAD='(1.0,-1.0)';
      PINUSE='BI';
    'PL5C':
      PIN_NUMBER='(0,0,0,0,0,F5,0)';
      BIDIRECTIONAL='TRUE';
      INPUT_LOAD='(-0.01,0.01)';
      OUTPUT_LOAD='(1.0,-1.0)';
      PINUSE='BI';
    'PL5D':
      PIN_NUMBER='(0,0,0,0,0,H6,0)';
      BIDIRECTIONAL='TRUE';
      INPUT_LOAD='(-0.01,0.01)';
      OUTPUT_LOAD='(1.0,-1.0)';
      PINUSE='BI';
    'VCCIO5':
      PIN_NUMBER='(0,0,0,0,0,E4,0)';
      PINUSE='POWER';
      NO_LOAD_CHECK='Both';
      NO_IO_CHECK='Both';
      NO_ASSERT_CHECK='TRUE';
      NO_DIR_CHECK='TRUE';
      ALLOW_CONNECT='TRUE';
    'PL4C':
      PIN_NUMBER='(0,0,0,0,0,G5,0)';
      BIDIRECTIONAL='TRUE';
      INPUT_LOAD='(-0.01,0.01)';
      OUTPUT_LOAD='(1.0,-1.0)';
      PINUSE='BI';
    'PL4D':
      PIN_NUMBER='(0,0,0,0,0,G4,0)';
      BIDIRECTIONAL='TRUE';
      INPUT_LOAD='(-0.01,0.01)';
      OUTPUT_LOAD='(1.0,-1.0)';
      PINUSE='BI';
    'PL4A':
      PIN_NUMBER='(0,0,0,0,0,F3,0)';
      BIDIRECTIONAL='TRUE';
      INPUT_LOAD='(-0.01,0.01)';
      OUTPUT_LOAD='(1.0,-1.0)';
      PINUSE='BI';
    'PL4B':
      PIN_NUMBER='(0,0,0,0,0,F1,0)';
      BIDIRECTIONAL='TRUE';
      INPUT_LOAD='(-0.01,0.01)';
      OUTPUT_LOAD='(1.0,-1.0)';
      PINUSE='BI';
    'GND_B2':
      PIN_NUMBER='(0,0,0,0,0,0,B2)';
      PINUSE='POWER';
      NO_LOAD_CHECK='Both';
      NO_IO_CHECK='Both';
      NO_ASSERT_CHECK='TRUE';
      NO_DIR_CHECK='TRUE';
      ALLOW_CONNECT='TRUE';
    'GND_B15':
      PIN_NUMBER='(0,0,0,0,0,0,B15)';
      PINUSE='POWER';
      NO_LOAD_CHECK='Both';
      NO_IO_CHECK='Both';
      NO_ASSERT_CHECK='TRUE';
      NO_DIR_CHECK='TRUE';
      ALLOW_CONNECT='TRUE';
    'GND_C3':
      PIN_NUMBER='(0,0,0,0,0,0,C3)';
      PINUSE='POWER';
      NO_LOAD_CHECK='Both';
      NO_IO_CHECK='Both';
      NO_ASSERT_CHECK='TRUE';
      NO_DIR_CHECK='TRUE';
      ALLOW_CONNECT='TRUE';
    'GND_C14':
      PIN_NUMBER='(0,0,0,0,0,0,C14)';
      PINUSE='POWER';
      NO_LOAD_CHECK='Both';
      NO_IO_CHECK='Both';
      NO_ASSERT_CHECK='TRUE';
      NO_DIR_CHECK='TRUE';
      ALLOW_CONNECT='TRUE';
    'GND_D4':
      PIN_NUMBER='(0,0,0,0,0,0,D4)';
      PINUSE='POWER';
      NO_LOAD_CHECK='Both';
      NO_IO_CHECK='Both';
      NO_ASSERT_CHECK='TRUE';
      NO_DIR_CHECK='TRUE';
      ALLOW_CONNECT='TRUE';
    'GND_D13':
      PIN_NUMBER='(0,0,0,0,0,0,D13)';
      PINUSE='POWER';
      NO_LOAD_CHECK='Both';
      NO_IO_CHECK='Both';
      NO_ASSERT_CHECK='TRUE';
      NO_DIR_CHECK='TRUE';
      ALLOW_CONNECT='TRUE';
    'GND_E5':
      PIN_NUMBER='(0,0,0,0,0,0,E5)';
      PINUSE='POWER';
      NO_LOAD_CHECK='Both';
      NO_IO_CHECK='Both';
      NO_ASSERT_CHECK='TRUE';
      NO_DIR_CHECK='TRUE';
      ALLOW_CONNECT='TRUE';
    'GND_E12':
      PIN_NUMBER='(0,0,0,0,0,0,E12)';
      PINUSE='POWER';
      NO_LOAD_CHECK='Both';
      NO_IO_CHECK='Both';
      NO_ASSERT_CHECK='TRUE';
      NO_DIR_CHECK='TRUE';
      ALLOW_CONNECT='TRUE';
    'GND_F6':
      PIN_NUMBER='(0,0,0,0,0,0,F6)';
      PINUSE='POWER';
      NO_LOAD_CHECK='Both';
      NO_IO_CHECK='Both';
      NO_ASSERT_CHECK='TRUE';
      NO_DIR_CHECK='TRUE';
      ALLOW_CONNECT='TRUE';
    'GND_F11':
      PIN_NUMBER='(0,0,0,0,0,0,F11)';
      PINUSE='POWER';
      NO_LOAD_CHECK='Both';
      NO_IO_CHECK='Both';
      NO_ASSERT_CHECK='TRUE';
      NO_DIR_CHECK='TRUE';
      ALLOW_CONNECT='TRUE';
    'GND_H8':
      PIN_NUMBER='(0,0,0,0,0,0,H8)';
      PINUSE='POWER';
      NO_LOAD_CHECK='Both';
      NO_IO_CHECK='Both';
      NO_ASSERT_CHECK='TRUE';
      NO_DIR_CHECK='TRUE';
      ALLOW_CONNECT='TRUE';
    'GND_H9':
      PIN_NUMBER='(0,0,0,0,0,0,H9)';
      PINUSE='POWER';
      NO_LOAD_CHECK='Both';
      NO_IO_CHECK='Both';
      NO_ASSERT_CHECK='TRUE';
      NO_DIR_CHECK='TRUE';
      ALLOW_CONNECT='TRUE';
    'GND_J8':
      PIN_NUMBER='(0,0,0,0,0,0,J8)';
      PINUSE='POWER';
      NO_LOAD_CHECK='Both';
      NO_IO_CHECK='Both';
      NO_ASSERT_CHECK='TRUE';
      NO_DIR_CHECK='TRUE';
      ALLOW_CONNECT='TRUE';
    'GND_J9':
      PIN_NUMBER='(0,0,0,0,0,0,J9)';
      PINUSE='POWER';
      NO_LOAD_CHECK='Both';
      NO_IO_CHECK='Both';
      NO_ASSERT_CHECK='TRUE';
      NO_DIR_CHECK='TRUE';
      ALLOW_CONNECT='TRUE';
    'GND_L6':
      PIN_NUMBER='(0,0,0,0,0,0,L6)';
      PINUSE='POWER';
      NO_LOAD_CHECK='Both';
      NO_IO_CHECK='Both';
      NO_ASSERT_CHECK='TRUE';
      NO_DIR_CHECK='TRUE';
      ALLOW_CONNECT='TRUE';
    'GND_L11':
      PIN_NUMBER='(0,0,0,0,0,0,L11)';
      PINUSE='POWER';
      NO_LOAD_CHECK='Both';
      NO_IO_CHECK='Both';
      NO_ASSERT_CHECK='TRUE';
      NO_DIR_CHECK='TRUE';
      ALLOW_CONNECT='TRUE';
    'GND_M5':
      PIN_NUMBER='(0,0,0,0,0,0,M5)';
      PINUSE='POWER';
      NO_LOAD_CHECK='Both';
      NO_IO_CHECK='Both';
      NO_ASSERT_CHECK='TRUE';
      NO_DIR_CHECK='TRUE';
      ALLOW_CONNECT='TRUE';
    'GND_M12':
      PIN_NUMBER='(0,0,0,0,0,0,M12)';
      PINUSE='POWER';
      NO_LOAD_CHECK='Both';
      NO_IO_CHECK='Both';
      NO_ASSERT_CHECK='TRUE';
      NO_DIR_CHECK='TRUE';
      ALLOW_CONNECT='TRUE';
    'GND_N4':
      PIN_NUMBER='(0,0,0,0,0,0,N4)';
      PINUSE='POWER';
      NO_LOAD_CHECK='Both';
      NO_IO_CHECK='Both';
      NO_ASSERT_CHECK='TRUE';
      NO_DIR_CHECK='TRUE';
      ALLOW_CONNECT='TRUE';
    'GND_N13':
      PIN_NUMBER='(0,0,0,0,0,0,N13)';
      PINUSE='POWER';
      NO_LOAD_CHECK='Both';
      NO_IO_CHECK='Both';
      NO_ASSERT_CHECK='TRUE';
      NO_DIR_CHECK='TRUE';
      ALLOW_CONNECT='TRUE';
    'GND_P3':
      PIN_NUMBER='(0,0,0,0,0,0,P3)';
      PINUSE='POWER';
      NO_LOAD_CHECK='Both';
      NO_IO_CHECK='Both';
      NO_ASSERT_CHECK='TRUE';
      NO_DIR_CHECK='TRUE';
      ALLOW_CONNECT='TRUE';
    'GND_P14':
      PIN_NUMBER='(0,0,0,0,0,0,P14)';
      PINUSE='POWER';
      NO_LOAD_CHECK='Both';
      NO_IO_CHECK='Both';
      NO_ASSERT_CHECK='TRUE';
      NO_DIR_CHECK='TRUE';
      ALLOW_CONNECT='TRUE';
    'GND_R2':
      PIN_NUMBER='(0,0,0,0,0,0,R2)';
      PINUSE='POWER';
      NO_LOAD_CHECK='Both';
      NO_IO_CHECK='Both';
      NO_ASSERT_CHECK='TRUE';
      NO_DIR_CHECK='TRUE';
      ALLOW_CONNECT='TRUE';
    'GND_R15':
      PIN_NUMBER='(0,0,0,0,0,0,R15)';
      PINUSE='POWER';
      NO_LOAD_CHECK='Both';
      NO_IO_CHECK='Both';
      NO_ASSERT_CHECK='TRUE';
      NO_DIR_CHECK='TRUE';
      ALLOW_CONNECT='TRUE';
    'NC1':
      PIN_NUMBER='(0,0,0,0,0,0,A2)';
      OUTPUT_TYPE='(TS,TS)';
      INPUT_LOAD='(-0.01,0.01)';
      OUTPUT_LOAD='(1.0,-1.0)';
      PINUSE='TRI';
    'VCC_T16':
      PIN_NUMBER='(0,0,0,0,0,0,T16)';
      PINUSE='POWER';
      NO_LOAD_CHECK='Both';
      NO_IO_CHECK='Both';
      NO_ASSERT_CHECK='TRUE';
      NO_DIR_CHECK='TRUE';
      ALLOW_CONNECT='TRUE';
    'VCC_T1':
      PIN_NUMBER='(0,0,0,0,0,0,T1)';
      PINUSE='POWER';
      NO_LOAD_CHECK='Both';
      NO_IO_CHECK='Both';
      NO_ASSERT_CHECK='TRUE';
      NO_DIR_CHECK='TRUE';
      ALLOW_CONNECT='TRUE';
    'VCC_K10':
      PIN_NUMBER='(0,0,0,0,0,0,K10)';
      PINUSE='POWER';
      NO_LOAD_CHECK='Both';
      NO_IO_CHECK='Both';
      NO_ASSERT_CHECK='TRUE';
      NO_DIR_CHECK='TRUE';
      ALLOW_CONNECT='TRUE';
    'VCC_K7':
      PIN_NUMBER='(0,0,0,0,0,0,K7)';
      PINUSE='POWER';
      NO_LOAD_CHECK='Both';
      NO_IO_CHECK='Both';
      NO_ASSERT_CHECK='TRUE';
      NO_DIR_CHECK='TRUE';
      ALLOW_CONNECT='TRUE';
    'VCC_G10':
      PIN_NUMBER='(0,0,0,0,0,0,G10)';
      PINUSE='POWER';
      NO_LOAD_CHECK='Both';
      NO_IO_CHECK='Both';
      NO_ASSERT_CHECK='TRUE';
      NO_DIR_CHECK='TRUE';
      ALLOW_CONNECT='TRUE';
    'VCC_G7':
      PIN_NUMBER='(0,0,0,0,0,0,G7)';
      PINUSE='POWER';
      NO_LOAD_CHECK='Both';
      NO_IO_CHECK='Both';
      NO_ASSERT_CHECK='TRUE';
      NO_DIR_CHECK='TRUE';
      ALLOW_CONNECT='TRUE';
    'VCC_A16':
      PIN_NUMBER='(0,0,0,0,0,0,A16)';
      PINUSE='POWER';
      NO_LOAD_CHECK='Both';
      NO_IO_CHECK='Both';
      NO_ASSERT_CHECK='TRUE';
      NO_DIR_CHECK='TRUE';
      ALLOW_CONNECT='TRUE';
    'VCC_A1':
      PIN_NUMBER='(0,0,0,0,0,0,A1)';
      PINUSE='POWER';
      NO_LOAD_CHECK='Both';
      NO_IO_CHECK='Both';
      NO_ASSERT_CHECK='TRUE';
      NO_DIR_CHECK='TRUE';
      ALLOW_CONNECT='TRUE';
  end_pin;
  body
      PART_NAME='LCMXO3LF2100C5BG256C';
      BODY_NAME='LCMXO3LF2100C5BG256C';
      PHYS_DES_PREFIX='U';
      CLASS='IC';
      STANDARD='';
      LIFECYCLE='';
      JEDEC_TYPE='BGA256_0-8_14X14';
      DESCRIPTION='ICOTHER(256P)LCMXO3LF-2100C-5BG256(CABGA';
      MANUFTR='LSC';
      MANUF_PN='LCMXO3LF-2100C-5BG256C';
      RD_CMPLS_LVL='EP(V1)';
      CMPLS_LVL='';
      FROM_PJ='MF5-STEVE';
      DIP_SMD='';
      DATA='LSC_LCMXO3LF-2100C-5BG256C.pdf';
      EE_CHECK_LIST='';
      FP_ECN='';
      PSL='';
      CREATOR='';
      STATUS='';
      MSD='NA';
      ESD_CDM='NA';
      ESD_HBM='NA';
      ESD_MM='NA';
      PIN_LENGTH_SHORT_PIN='0 MILS';
      PIN_LENGTH_LONG_PIN='0 MILS';
      CREATEDAY='20180326';
      PARENT_PART_TYPE='LCMXO3LF2100C5BG256C';
      PARENT_PPT='LCMXO3LF2100C5BG256C';
      PARENT_PPT_PART='LCMXO3LF2100C5BG256C-LCMXO3LF-2100C-5BG256C,SMLF,IC,AJ021000T03';
  end_body;
end_primitive;
primitive 'M24128BWDW6TP-M24128-BWDW6TP,SA';
  pin
    'VCC':
      PIN_NUMBER='(8)';
      PINUSE='POWER';
      NO_LOAD_CHECK='Both';
      NO_IO_CHECK='Both';
      NO_ASSERT_CHECK='TRUE';
      NO_DIR_CHECK='TRUE';
      ALLOW_CONNECT='TRUE';
    'WC#':
      PIN_NUMBER='(7)';
      INPUT_LOAD='(-0.01,0.01)';
      PINUSE='IN';
    'SCL':
      PIN_NUMBER='(6)';
      INPUT_LOAD='(-0.01,0.01)';
      PINUSE='IN';
    'SDA':
      PIN_NUMBER='(5)';
      BIDIRECTIONAL='TRUE';
      INPUT_LOAD='(-0.01,0.01)';
      OUTPUT_LOAD='(1.0,-1.0)';
      PINUSE='BI';
    'VSS':
      PIN_NUMBER='(4)';
      PINUSE='POWER';
      NO_LOAD_CHECK='Both';
      NO_IO_CHECK='Both';
      NO_ASSERT_CHECK='TRUE';
      NO_DIR_CHECK='TRUE';
      ALLOW_CONNECT='TRUE';
    'E2':
      PIN_NUMBER='(3)';
      INPUT_LOAD='(-0.01,0.01)';
      PINUSE='IN';
    'E1':
      PIN_NUMBER='(2)';
      INPUT_LOAD='(-0.01,0.01)';
      PINUSE='IN';
    'E0':
      PIN_NUMBER='(1)';
      INPUT_LOAD='(-0.01,0.01)';
      PINUSE='IN';
  end_pin;
  body
      PART_NAME='M24128BWDW6TP';
      BODY_NAME='M24128BWDW6TP';
      PHYS_DES_PREFIX='U';
      CLASS='IC';
      STANDARD='';
      LIFECYCLE='';
      JEDEC_TYPE='TSSOP8_0-65_3X4-4XG';
      DESCRIPTION='IC(8P)M24128-BWDW6TP(TSSOP)';
      MANUFTR='SGT';
      MANUF_PN='M24128-BWDW6TP';
      RD_CMPLS_LVL='EP';
      CMPLS_LVL='EP';
      FROM_PJ='S83-JOSEPH';
      DIP_SMD='';
      DATA='SGT_M24128-BWDW6TP.pdf';
      EE_CHECK_LIST='';
      FP_ECN='TSSOP8_Foortprint.docx';
      PSL='';
      CREATOR='';
      STATUS='';
      MSD='NA';
      ESD_CDM='NA';
      ESD_HBM='NA';
      ESD_MM='NA';
      PIN_LENGTH_SHORT_PIN='0 MILS';
      PIN_LENGTH_LONG_PIN='0 MILS';
      CREATEDAY='20190828';
      PARENT_PART_TYPE='M24128BWDW6TP';
      PARENT_PPT='M24128BWDW6TP';
      PARENT_PPT_PART='M24128BWDW6TP-M24128-BWDW6TP,SMLF,IC,AKE30Z0K610';
  end_body;
end_primitive;
primitive 'MC74VHC1G07DFT2G-MC74VHC1G07DFA';
  pin
    'VCC':
      PIN_NUMBER='(5)';
      PINUSE='POWER';
      NO_LOAD_CHECK='Both';
      NO_IO_CHECK='Both';
      NO_ASSERT_CHECK='TRUE';
      NO_DIR_CHECK='TRUE';
      ALLOW_CONNECT='TRUE';
    'IN_A':
      PIN_NUMBER='(2)';
      INPUT_LOAD='(-0.01,0.01)';
      PINUSE='IN';
    'GND':
      PIN_NUMBER='(3)';
      PINUSE='POWER';
      NO_LOAD_CHECK='Both';
      NO_IO_CHECK='Both';
      NO_ASSERT_CHECK='TRUE';
      NO_DIR_CHECK='TRUE';
      ALLOW_CONNECT='TRUE';
    'OUT_Y':
      PIN_NUMBER='(4)';
      OUTPUT_LOAD='(1.0,-1.0)';
      PINUSE='OUT';
    'NC1':
      PIN_NUMBER='(1)';
      OUTPUT_TYPE='(TS,TS)';
      INPUT_LOAD='(-0.01,0.01)';
      OUTPUT_LOAD='(1.0,-1.0)';
      PINUSE='TRI';
  end_pin;
  body
      PART_NAME='MC74VHC1G07DFT2G';
      BODY_NAME='MC74VHC1G07DFT2G';
      PHYS_DES_PREFIX='U';
      CLASS='IC';
      STANDARD='';
      LIFECYCLE='';
      JEDEC_TYPE='SC70-5XA';
      DESCRIPTION='IC OTHER(5P)MC74VHC1G07DFT2G(SOT-353)';
      MANUFTR='ONS';
      MANUF_PN='MC74VHC1G07DFT2G';
      RD_CMPLS_LVL='EP(V1)';
      CMPLS_LVL='EP(V1)';
      FROM_PJ='F0T-FISHER';
      DIP_SMD='';
      DATA='ONS_MC74VHC1G07DFT2G.pdf';
      EE_CHECK_LIST='';
      FP_ECN='';
      PSL='';
      CREATOR='';
      STATUS='';
      MSD='';
      ESD_CDM='';
      ESD_HBM='';
      ESD_MM='';
      PIN_LENGTH_SHORT_PIN='0 MILS';
      PIN_LENGTH_LONG_PIN='0 MILS';
      CREATEDAY='20211021';
      PARENT_PART_TYPE='MC74VHC1G07DFT2G';
      PARENT_PPT='MC74VHC1G07DFT2G';
      PARENT_PPT_PART='MC74VHC1G07DFT2G-MC74VHC1G07DFT2G,SMLF,EMPTY,AL001G07003';
  end_body;
end_primitive;
primitive 'MC74VHC1G32DTT1G-MC74VHC1G32DTA';
  pin
    'OUT_Y':
      PIN_NUMBER='(4)';
      OUTPUT_LOAD='(1.0,-1.0)';
      PINUSE='OUT';
    'IN_B':
      PIN_NUMBER='(1)';
      INPUT_LOAD='(-0.01,0.01)';
      PINUSE='IN';
    'IN_A':
      PIN_NUMBER='(2)';
      INPUT_LOAD='(-0.01,0.01)';
      PINUSE='IN';
    'GND':
      PIN_NUMBER='(3)';
      PINUSE='POWER';
      NO_LOAD_CHECK='Both';
      NO_IO_CHECK='Both';
      NO_ASSERT_CHECK='TRUE';
      NO_DIR_CHECK='TRUE';
      ALLOW_CONNECT='TRUE';
    'VCC':
      PIN_NUMBER='(5)';
      PINUSE='POWER';
      NO_LOAD_CHECK='Both';
      NO_IO_CHECK='Both';
      NO_ASSERT_CHECK='TRUE';
      NO_DIR_CHECK='TRUE';
      ALLOW_CONNECT='TRUE';
  end_pin;
  body
      PART_NAME='MC74VHC1G32DTT1G';
      BODY_NAME='MC74VHC1G32DTT1G';
      PHYS_DES_PREFIX='U';
      CLASS='IC';
      STANDARD='';
      LIFECYCLE='';
      JEDEC_TYPE='SOT23-5_0-95_3X1-5';
      DESCRIPTION='IC OTHER (5P)MC74VHC1G32DTT1G(SOT-23)';
      MANUFTR='ONS';
      MANUF_PN='MC74VHC1G32DTT1G';
      RD_CMPLS_LVL='EP(V1)';
      CMPLS_LVL='EP(V1)';
      FROM_PJ='F0T-FISHER';
      DIP_SMD='';
      DATA='ONS_MC74VHC1G32DTT1G.pdf';
      EE_CHECK_LIST='';
      FP_ECN='';
      PSL='';
      CREATOR='';
      STATUS='';
      MSD='';
      ESD_CDM='';
      ESD_HBM='';
      ESD_MM='';
      PIN_LENGTH_SHORT_PIN='0 MILS';
      PIN_LENGTH_LONG_PIN='0 MILS';
      CREATEDAY='20211006';
      PARENT_PART_TYPE='MC74VHC1G32DTT1G';
      PARENT_PPT='MC74VHC1G32DTT1G';
      PARENT_PPT_PART='MC74VHC1G32DTT1G-MC74VHC1G32DTT1G,SMLF,IC,AL001G32031';
  end_body;
end_primitive;
primitive 'ME_DUMMY_SYMBOL-PB-E1_SMALL,MEA';
  pin
  end_pin;
  body
      PART_NAME='ME_DUMMY_SYMBOL';
      BODY_NAME='ME_DUMMY_SYMBOL';
      PHYS_DES_PREFIX='ME';
      CLASS='MECHANICAL';
      STANDARD='';
      LIFECYCLE='';
      JEDEC_TYPE='PB-E1_SMALL';
      DESCRIPTION='PB-E1_SMALL';
      MANUFTR='';
      MANUF_PN='';
      RD_CMPLS_LVL='';
      CMPLS_LVL='';
      DIP_SMD='';
      FROM_PJ='';
      DATA='';
      FP_ECN='';
      EE_CHECK_LIST='';
      PSL='';
      PREFERENCE='';
      CREATOR='';
      CREATEDAY='20210923';
      STATUS='';
      ESD_CDM='';
      ESD_HBM='';
      ESD_MM='';
      MSD='';
      PIN_LENGTH_LONG_PIN='';
      PIN_LENGTH_SHORT_PIN='';
      PARENT_PART_TYPE='ME_DUMMY_SYMBOL';
      PARENT_PPT='ME_DUMMY_SYMBOL';
      PARENT_PPT_PART='ME_DUMMY_SYMBOL-PB-E1_SMALL,MECH,EMPTY,DUMMY3';
  end_body;
end_primitive;
primitive 'ME_DUMMY_SYMBOL-QUANTA_LOGO_7XA';
  pin
  end_pin;
  body
      PART_NAME='ME_DUMMY_SYMBOL';
      BODY_NAME='ME_DUMMY_SYMBOL';
      PHYS_DES_PREFIX='ME';
      CLASS='MECHANICAL';
      STANDARD='';
      LIFECYCLE='';
      JEDEC_TYPE='QUANTA_LOGO_7X26';
      DESCRIPTION='QUANTA_LOGO_7X26';
      MANUFTR='';
      MANUF_PN='';
      RD_CMPLS_LVL='';
      CMPLS_LVL='';
      DIP_SMD='';
      FROM_PJ='';
      DATA='';
      FP_ECN='';
      EE_CHECK_LIST='';
      PSL='';
      PREFERENCE='';
      CREATOR='';
      CREATEDAY='20141104';
      STATUS='';
      ESD_CDM='';
      ESD_HBM='';
      ESD_MM='';
      MSD='';
      PIN_LENGTH_LONG_PIN='';
      PIN_LENGTH_SHORT_PIN='';
      PARENT_PART_TYPE='ME_DUMMY_SYMBOL';
      PARENT_PPT='ME_DUMMY_SYMBOL';
      PARENT_PPT_PART='ME_DUMMY_SYMBOL-QUANTA_LOGO_7X26,MECH,EMPTY,DUMMY1';
  end_body;
end_primitive;
primitive 'ME_DUMMY_SYMBOL-SNLABEL_7X7,MEA';
  pin
  end_pin;
  body
      PART_NAME='ME_DUMMY_SYMBOL';
      BODY_NAME='ME_DUMMY_SYMBOL';
      PHYS_DES_PREFIX='ME';
      CLASS='MECHANICAL';
      STANDARD='';
      LIFECYCLE='';
      JEDEC_TYPE='SNLABEL_7X7';
      DESCRIPTION='SNLABEL_7X7';
      MANUFTR='';
      MANUF_PN='';
      RD_CMPLS_LVL='';
      CMPLS_LVL='';
      DIP_SMD='';
      FROM_PJ='';
      DATA='';
      FP_ECN='';
      EE_CHECK_LIST='';
      PSL='';
      PREFERENCE='';
      CREATOR='';
      CREATEDAY='20200526';
      STATUS='';
      ESD_CDM='';
      ESD_HBM='';
      ESD_MM='';
      MSD='';
      PIN_LENGTH_LONG_PIN='';
      PIN_LENGTH_SHORT_PIN='';
      PARENT_PART_TYPE='ME_DUMMY_SYMBOL';
      PARENT_PPT='ME_DUMMY_SYMBOL';
      PARENT_PPT_PART='ME_DUMMY_SYMBOL-SNLABEL_7X7,MECH,EMPTY,DUMMY69';
  end_body;
end_primitive;
primitive 'ME_DUMMY_SYMBOL-WEEE,MECH,EMPTA';
  pin
  end_pin;
  body
      PART_NAME='ME_DUMMY_SYMBOL';
      BODY_NAME='ME_DUMMY_SYMBOL';
      PHYS_DES_PREFIX='ME';
      CLASS='MECHANICAL';
      STANDARD='';
      LIFECYCLE='';
      JEDEC_TYPE='WEEE';
      DESCRIPTION='WEEE';
      MANUFTR='';
      MANUF_PN='';
      RD_CMPLS_LVL='';
      CMPLS_LVL='';
      DIP_SMD='';
      FROM_PJ='';
      DATA='';
      FP_ECN='';
      EE_CHECK_LIST='';
      PSL='';
      PREFERENCE='';
      CREATOR='';
      CREATEDAY='20141104';
      STATUS='';
      ESD_CDM='';
      ESD_HBM='';
      ESD_MM='';
      MSD='';
      PIN_LENGTH_LONG_PIN='';
      PIN_LENGTH_SHORT_PIN='';
      PARENT_PART_TYPE='ME_DUMMY_SYMBOL';
      PARENT_PPT='ME_DUMMY_SYMBOL';
      PARENT_PPT_PART='ME_DUMMY_SYMBOL-WEEE,MECH,EMPTY,DUMMY2';
  end_body;
end_primitive;
primitive 'MMBT39047F-MMBT3904-7-F,SMLF,IA';
  pin
    '1':
      PIN_NUMBER='(B)';
      INPUT_LOAD='(-0.01,0.01)';
      PINUSE='IN';
    '2':
      PIN_NUMBER='(E)';
      BIDIRECTIONAL='TRUE';
      INPUT_LOAD='(-0.01,0.01)';
      OUTPUT_LOAD='(1.0,-1.0)';
      PINUSE='BI';
    '3':
      PIN_NUMBER='(C)';
      BIDIRECTIONAL='TRUE';
      INPUT_LOAD='(-0.01,0.01)';
      OUTPUT_LOAD='(1.0,-1.0)';
      PINUSE='BI';
  end_pin;
  body
      PART_NAME='MMBT39047F';
      BODY_NAME='MMBT39047F';
      PHYS_DES_PREFIX='Q';
      CLASS='IC';
      JEDEC_TYPE='SOT23_BEC';
      DESCRIPTION='TRANS SMD MMBT3904-7-F(40V,200MA,8W)';
      MANUFTR='DDS';
      MANUF_PN='MMBT3904-7-F';
      RD_CMPLS_LVL='EP(V1)';
      CMPLS_LVL='EP(V1)';
      DIP_SMD='';
      FP_ECN='';
      FROM_PJ='T2L-CHEESE';
      DATA='DDS_MMBT3904-7-F.pdf';
      EE_CHECK_LIST='';
      STANDARD='End of Design';
      PSL='';
      PREFERENCE='';
      LIFECYCLE='Comp-Approve';
      CREATOR='';
      CREATEDAY='20120131';
      STATUS='';
      PARENT_PART_TYPE='MMBT39047F';
      PARENT_PPT='MMBT39047F';
      PARENT_PPT_PART='MMBT39047F-MMBT3904-7-F,SMLF,IC,BA0390400H0';
  end_body;
end_primitive;
primitive 'MOSFET_DUAL_6P-2N7002KDW,SMLF,A';
  pin
    'G1':
      PIN_NUMBER='(2)';
      BIDIRECTIONAL='TRUE';
      INPUT_LOAD='(-0.01,0.01)';
      OUTPUT_LOAD='(1.0,-1.0)';
      PINUSE='BI';
    'G2':
      PIN_NUMBER='(5)';
      BIDIRECTIONAL='TRUE';
      INPUT_LOAD='(-0.01,0.01)';
      OUTPUT_LOAD='(1.0,-1.0)';
      PINUSE='BI';
    'S1':
      PIN_NUMBER='(1)';
      BIDIRECTIONAL='TRUE';
      INPUT_LOAD='(-0.01,0.01)';
      OUTPUT_LOAD='(1.0,-1.0)';
      PINUSE='BI';
    'S2':
      PIN_NUMBER='(4)';
      BIDIRECTIONAL='TRUE';
      INPUT_LOAD='(-0.01,0.01)';
      OUTPUT_LOAD='(1.0,-1.0)';
      PINUSE='BI';
    'D1':
      PIN_NUMBER='(6)';
      BIDIRECTIONAL='TRUE';
      INPUT_LOAD='(-0.01,0.01)';
      OUTPUT_LOAD='(1.0,-1.0)';
      PINUSE='BI';
    'D2':
      PIN_NUMBER='(3)';
      BIDIRECTIONAL='TRUE';
      INPUT_LOAD='(-0.01,0.01)';
      OUTPUT_LOAD='(1.0,-1.0)';
      PINUSE='BI';
  end_pin;
  body
      PART_NAME='MOSFET_DUAL_6P';
      BODY_NAME='MOSFET_DUAL_6P';
      PHYS_DES_PREFIX='Q';
      CLASS='IC';
      STANDARD='';
      LIFECYCLE='';
      JEDEC_TYPE='SOT363XD';
      DESCRIPTION='TRANS MOS 2N7002KDW(60V115MA,0.2W)SOT363';
      MANUFTR='PJT';
      MANUF_PN='2N7002KDW';
      RD_CMPLS_LVL='EP(V1)';
      CMPLS_LVL='EP(V1)';
      DIP_SMD='';
      FP_ECN='';
      FROM_PJ='F06S-KENG-YU';
      DATA='PJT_2N7002KDW.pdf';
      EE_CHECK_LIST='';
      STATUS='';
      PSL='';
      PREFERENCE='';
      CREATOR='';
      CREATEDAY='20140113';
      PARENT_PART_TYPE='MOSFET_DUAL_6P';
      PARENT_PPT='MOSFET_DUAL_6P';
      PARENT_PPT_PART='MOSFET_DUAL_6P-2N7002KDW,SMLF,IC,BAM70020047';
  end_body;
end_primitive;
primitive 'MOSFET_NCH_4D1S-NTGS4141NT1G,SA';
  pin
    '1':
      PIN_NUMBER='(1)';
      BIDIRECTIONAL='TRUE';
      INPUT_LOAD='(-0.01,0.01)';
      OUTPUT_LOAD='(1.0,-1.0)';
      PINUSE='BI';
    '6':
      PIN_NUMBER='(6)';
      BIDIRECTIONAL='TRUE';
      INPUT_LOAD='(-0.01,0.01)';
      OUTPUT_LOAD='(1.0,-1.0)';
      PINUSE='BI';
    '3':
      PIN_NUMBER='(3)';
      INPUT_LOAD='(-0.01,0.01)';
      PINUSE='IN';
    '2':
      PIN_NUMBER='(2)';
      BIDIRECTIONAL='TRUE';
      INPUT_LOAD='(-0.01,0.01)';
      OUTPUT_LOAD='(1.0,-1.0)';
      PINUSE='BI';
    '4':
      PIN_NUMBER='(4)';
      BIDIRECTIONAL='TRUE';
      INPUT_LOAD='(-0.01,0.01)';
      OUTPUT_LOAD='(1.0,-1.0)';
      PINUSE='BI';
    '5':
      PIN_NUMBER='(5)';
      BIDIRECTIONAL='TRUE';
      INPUT_LOAD='(-0.01,0.01)';
      OUTPUT_LOAD='(1.0,-1.0)';
      PINUSE='BI';
  end_pin;
  body
      PART_NAME='MOSFET_NCH_4D1S';
      BODY_NAME='MOSFET_NCH_4D1S';
      PHYS_DES_PREFIX='Q';
      CLASS='IC';
      STANDARD='End of Design';
      LIFECYCLE='Comp-Approve';
      JEDEC_TYPE='TSOP6XB';
      DESCRIPTION='TRANS MOS NTGS4141NT1G(30V,7.0A,TSOP6)';
      MANUFTR='ONS';
      MANUF_PN='NTGS4141NT1G';
      RD_CMPLS_LVL='EP(V1)';
      CMPLS_LVL='EP(V1)';
      DIP_SMD='';
      FP_ECN='';
      FROM_PJ='T2H-GAVEN';
      DATA='ONS_NTGS4141NT1G_REV0.pdf';
      EE_CHECK_LIST='';
      STATUS='';
      PSL='';
      PREFERENCE='';
      CREATOR='';
      CREATEDAY='20141104';
      PARENT_PART_TYPE='MOSFET_NCH_4D1S';
      PARENT_PPT='MOSFET_NCH_4D1S';
      PARENT_PPT_PART='MOSFET_NCH_4D1S-NTGS4141NT1G,SMLF,IC,BAM41410005';
  end_body;
end_primitive;
primitive 'MOSFET_NCH_DUAL-2N7002KDW,SMLFA';
  pin
    'S1':
      PIN_NUMBER='(1,0)';
      BIDIRECTIONAL='TRUE';
      INPUT_LOAD='(-0.01,0.01)';
      OUTPUT_LOAD='(1.0,-1.0)';
      PINUSE='BI';
    'G1':
      PIN_NUMBER='(2,0)';
      BIDIRECTIONAL='TRUE';
      INPUT_LOAD='(-0.01,0.01)';
      OUTPUT_LOAD='(1.0,-1.0)';
      PINUSE='BI';
    'D1':
      PIN_NUMBER='(6,0)';
      BIDIRECTIONAL='TRUE';
      INPUT_LOAD='(-0.01,0.01)';
      OUTPUT_LOAD='(1.0,-1.0)';
      PINUSE='BI';
    'D2':
      PIN_NUMBER='(0,3)';
      BIDIRECTIONAL='TRUE';
      INPUT_LOAD='(-0.01,0.01)';
      OUTPUT_LOAD='(1.0,-1.0)';
      PINUSE='BI';
    'G2':
      PIN_NUMBER='(0,5)';
      BIDIRECTIONAL='TRUE';
      INPUT_LOAD='(-0.01,0.01)';
      OUTPUT_LOAD='(1.0,-1.0)';
      PINUSE='BI';
    'S2':
      PIN_NUMBER='(0,4)';
      BIDIRECTIONAL='TRUE';
      INPUT_LOAD='(-0.01,0.01)';
      OUTPUT_LOAD='(1.0,-1.0)';
      PINUSE='BI';
  end_pin;
  body
      PART_NAME='MOSFET_NCH_DUAL';
      BODY_NAME='MOSFET_NCH_DUAL';
      PHYS_DES_PREFIX='Q';
      CLASS='IC';
      STANDARD='';
      LIFECYCLE='';
      JEDEC_TYPE='SOT363XD';
      DESCRIPTION='TRANS MOS 2N7002KDW(60V115MA,0.2W)SOT363';
      MANUFTR='PJT';
      MANUF_PN='2N7002KDW';
      RD_CMPLS_LVL='EP(V1)';
      CMPLS_LVL='EP(V1)';
      DIP_SMD='';
      FP_ECN='';
      FROM_PJ='F06-GLEN';
      DATA='ONS_NTJD4001N.pdf';
      EE_CHECK_LIST='';
      PSL='';
      PREFERENCE='';
      CREATOR='';
      CREATEDAY='20140923';
      STATUS='';
      PARENT_PART_TYPE='MOSFET_NCH_DUAL';
      PARENT_PPT='MOSFET_NCH_DUAL';
      PARENT_PPT_PART='MOSFET_NCH_DUAL-2N7002KDW,SMLF,IC,BAM70020047';
  end_body;
end_primitive;
primitive 'MOSFET_NCH_DUAL-PJT138K,SMLF,IA';
  pin
    'S1':
      PIN_NUMBER='(1,0)';
      BIDIRECTIONAL='TRUE';
      INPUT_LOAD='(-0.01,0.01)';
      OUTPUT_LOAD='(1.0,-1.0)';
      PINUSE='BI';
    'G1':
      PIN_NUMBER='(2,0)';
      BIDIRECTIONAL='TRUE';
      INPUT_LOAD='(-0.01,0.01)';
      OUTPUT_LOAD='(1.0,-1.0)';
      PINUSE='BI';
    'D1':
      PIN_NUMBER='(6,0)';
      BIDIRECTIONAL='TRUE';
      INPUT_LOAD='(-0.01,0.01)';
      OUTPUT_LOAD='(1.0,-1.0)';
      PINUSE='BI';
    'D2':
      PIN_NUMBER='(0,3)';
      BIDIRECTIONAL='TRUE';
      INPUT_LOAD='(-0.01,0.01)';
      OUTPUT_LOAD='(1.0,-1.0)';
      PINUSE='BI';
    'G2':
      PIN_NUMBER='(0,5)';
      BIDIRECTIONAL='TRUE';
      INPUT_LOAD='(-0.01,0.01)';
      OUTPUT_LOAD='(1.0,-1.0)';
      PINUSE='BI';
    'S2':
      PIN_NUMBER='(0,4)';
      BIDIRECTIONAL='TRUE';
      INPUT_LOAD='(-0.01,0.01)';
      OUTPUT_LOAD='(1.0,-1.0)';
      PINUSE='BI';
  end_pin;
  body
      PART_NAME='MOSFET_NCH_DUAL';
      BODY_NAME='MOSFET_NCH_DUAL';
      PHYS_DES_PREFIX='Q';
      CLASS='IC';
      STANDARD='';
      LIFECYCLE='';
      JEDEC_TYPE='SOT363XD';
      DESCRIPTION='TRANS MOSFET PJT138K(50V,0.36A,0.236W)';
      MANUFTR='PJT';
      MANUF_PN='PJT138K';
      RD_CMPLS_LVL='EP(V1)';
      CMPLS_LVL='EP(V1)';
      DIP_SMD='';
      FP_ECN='';
      FROM_PJ='F09-MARK';
      DATA='PJT_PJT138K_revJULY-25-2013.pdf';
      EE_CHECK_LIST='';
      PSL='';
      PREFERENCE='';
      CREATOR='';
      CREATEDAY='20160617';
      STATUS='';
      PARENT_PART_TYPE='MOSFET_NCH_DUAL';
      PARENT_PPT='MOSFET_NCH_DUAL';
      PARENT_PPT_PART='MOSFET_NCH_DUAL-PJT138K,SMLF,IC,BAM138K0003';
  end_body;
end_primitive;
primitive 'MOSFET_N_GSD-DMG6968U-7,SMLF,IA';
  pin
    'GATE':
      PIN_NUMBER='(G)';
      INPUT_LOAD='(-0.01,0.01)';
      PINUSE='IN';
    'SOURCE':
      PIN_NUMBER='(S)';
      BIDIRECTIONAL='TRUE';
      INPUT_LOAD='(-0.01,0.01)';
      OUTPUT_LOAD='(1.0,-1.0)';
      PINUSE='BI';
    'DRAIN':
      PIN_NUMBER='(D)';
      BIDIRECTIONAL='TRUE';
      INPUT_LOAD='(-0.01,0.01)';
      OUTPUT_LOAD='(1.0,-1.0)';
      PINUSE='BI';
  end_pin;
  body
      PART_NAME='MOSFET_N_GSD';
      BODY_NAME='MOSFET_N_GSD';
      PHYS_DES_PREFIX='Q';
      CLASS='IC';
      STANDARD='End of Design';
      LIFECYCLE='Comp-Approve';
      JEDEC_TYPE='SOT23_GDSXC';
      DESCRIPTION='TRANS MOS DMG6968U-7(20V,6.5A,1.3W)SOT23';
      MANUFTR='DDS';
      MANUF_PN='DMG6968U-7';
      RD_CMPLS_LVL='EP(V1)';
      CMPLS_LVL='';
      DIP_SMD='';
      FP_ECN='';
      FROM_PJ='S1N-AI-JU';
      DATA='DDS_DMG6968U.pdf';
      EE_CHECK_LIST='';
      PSL='';
      PREFERENCE='';
      CREATOR='';
      CREATEDAY='20120801';
      STATUS='';
      PARENT_PART_TYPE='MOSFET_N_GSD';
      PARENT_PPT='MOSFET_N_GSD';
      PARENT_PPT_PART='MOSFET_N_GSD-DMG6968U-7,SMLF,IC,BAM69680000';
  end_body;
end_primitive;
primitive 'MOSFET_N_GSD-NX7002AK,SMLF,IC,A';
  pin
    'GATE':
      PIN_NUMBER='(G)';
      INPUT_LOAD='(-0.01,0.01)';
      PINUSE='IN';
    'SOURCE':
      PIN_NUMBER='(S)';
      BIDIRECTIONAL='TRUE';
      INPUT_LOAD='(-0.01,0.01)';
      OUTPUT_LOAD='(1.0,-1.0)';
      PINUSE='BI';
    'DRAIN':
      PIN_NUMBER='(D)';
      BIDIRECTIONAL='TRUE';
      INPUT_LOAD='(-0.01,0.01)';
      OUTPUT_LOAD='(1.0,-1.0)';
      PINUSE='BI';
  end_pin;
  body
      PART_NAME='MOSFET_N_GSD';
      BODY_NAME='MOSFET_N_GSD';
      PHYS_DES_PREFIX='Q';
      CLASS='IC';
      STANDARD='End of Design';
      LIFECYCLE='Comp-Approve';
      JEDEC_TYPE='SOT23_GDSXE';
      DESCRIPTION='TRANS MOS NX7002AK(60V,0.19A,0.325W)SMD';
      MANUFTR='NXP';
      MANUF_PN='NX7002AK';
      RD_CMPLS_LVL='EP(V1)';
      CMPLS_LVL='';
      DIP_SMD='';
      FP_ECN='';
      FROM_PJ='S1N-AI-JU';
      DATA='NXP_NX7002AK.pdf';
      EE_CHECK_LIST='';
      PSL='';
      PREFERENCE='';
      CREATOR='';
      CREATEDAY='20120801';
      STATUS='';
      PARENT_PART_TYPE='MOSFET_N_GSD';
      PARENT_PPT='MOSFET_N_GSD';
      PARENT_PPT_PART='MOSFET_N_GSD-NX7002AK,SMLF,IC,BAM70020062';
  end_body;
end_primitive;
primitive 'MOSFET_N_SMLF-BSS138K,BSS138K,A';
  pin
    'GATE':
      PIN_NUMBER='(G)';
      INPUT_LOAD='(-0.01,0.01)';
      PINUSE='IN';
    'DRAIN':
      PIN_NUMBER='(D)';
      OUTPUT_LOAD='(1.0,-1.0)';
      PINUSE='OUT';
    'SOURCE':
      PIN_NUMBER='(S)';
      INPUT_LOAD='(-0.01,0.01)';
      OUTPUT_LOAD='(1.0,-1.0)';
      BIDIRECTIONAL='TRUE';
      PINUSE='BI';
  end_pin;
  body
      PHYS_DES_PREFIX='U';
      CLASS='IC';
      PART_NAME='MOSFET_N';
      BODY_NAME='MOSFET_N';
      STANDARD='End of Design';
      LIFECYCLE='Comp-Approve';
      JEDEC_TYPE='SOT23_GDSXD';
      DESCRIPTION='TRANS MOS BSS138K(50V,0.22A,0.35W)';
      COMPONENT_TYPE='SMALLSMT';
      LEAD_LENGTH='';
      LPID='';
      DAY='20150826';
      PARENT_PART_TYPE='MOSFET_N';
      PARENT_PPT='MOSFET_N';
      PARENT_PPT_PART='MOSFET_N_SMLF-BSS138K,BSS138K,IC,BAM138K0000';
  end_body;
end_primitive;
primitive 'MOSFET_PCH_GDS-NTR1P02LT1G,SMLA';
  pin
    'D':
      PIN_NUMBER='(D)';
      BIDIRECTIONAL='TRUE';
      INPUT_LOAD='(-0.01,0.01)';
      OUTPUT_LOAD='(1.0,-1.0)';
      PINUSE='BI';
    'G':
      PIN_NUMBER='(G)';
      INPUT_LOAD='(-0.01,0.01)';
      PINUSE='IN';
    'S':
      PIN_NUMBER='(S)';
      BIDIRECTIONAL='TRUE';
      INPUT_LOAD='(-0.01,0.01)';
      OUTPUT_LOAD='(1.0,-1.0)';
      PINUSE='BI';
  end_pin;
  body
      PART_NAME='MOSFET_PCH_GDS';
      BODY_NAME='MOSFET_PCH_GDS';
      PHYS_DES_PREFIX='Q';
      CLASS='IC';
      STANDARD='End of Design';
      LIFECYCLE='Comp-Approve';
      JEDEC_TYPE='SOT23_GDS_2-9X1-3XC';
      DESCRIPTION='TRANS MOSFET NTR1P02LT1G(-20V,SOT-23)';
      MANUFTR='ONS';
      MANUF_PN='NTR1P02LT1G';
      RD_CMPLS_LVL='EP(V1)';
      CMPLS_LVL='EP(V1)';
      DIP_SMD='';
      FP_ECN='';
      FROM_PJ='JG7-ALLEN';
      DATA='ONS_NTR1P02LT1G.pdf';
      EE_CHECK_LIST='';
      STATUS='';
      PSL='';
      PREFERENCE='';
      CREATOR='';
      CREATEDAY='20200907';
      PARENT_PART_TYPE='MOSFET_PCH_GDS';
      PARENT_PPT='MOSFET_PCH_GDS';
      PARENT_PPT_PART='MOSFET_PCH_GDS-NTR1P02LT1G,SMLF,EMPTY,BAM1P020000';
  end_body;
end_primitive;
primitive 'MPQ8626GDZ-MPQ8626GD-Z,SMLF,ICA';
  pin
    'VIN':
      PIN_NUMBER='(3)';
      INPUT_LOAD='(-0.01,0.01)';
      PINUSE='IN';
    'PGOOD':
      PIN_NUMBER='(9)';
      OUTPUT_LOAD='(1.0,-1.0)';
      PINUSE='OUT';
    'PGND2':
      PIN_NUMBER='(14)';
      PINUSE='POWER';
      NO_LOAD_CHECK='Both';
      NO_IO_CHECK='Both';
      NO_ASSERT_CHECK='TRUE';
      NO_DIR_CHECK='TRUE';
      ALLOW_CONNECT='TRUE';
    'EN':
      PIN_NUMBER='(5)';
      INPUT_LOAD='(-0.01,0.01)';
      PINUSE='IN';
    'BST':
      PIN_NUMBER='(10)';
      INPUT_LOAD='(-0.01,0.01)';
      PINUSE='IN';
    'FB':
      PIN_NUMBER='(6)';
      INPUT_LOAD='(-0.01,0.01)';
      PINUSE='IN';
    'AGND':
      PIN_NUMBER='(7)';
      PINUSE='POWER';
      NO_LOAD_CHECK='Both';
      NO_IO_CHECK='Both';
      NO_ASSERT_CHECK='TRUE';
      NO_DIR_CHECK='TRUE';
      ALLOW_CONNECT='TRUE';
    'VCC':
      PIN_NUMBER='(13)';
      OUTPUT_LOAD='(1.0,-1.0)';
      PINUSE='OUT';
    'PGND1':
      PIN_NUMBER='(1)';
      PINUSE='POWER';
      NO_LOAD_CHECK='Both';
      NO_IO_CHECK='Both';
      NO_ASSERT_CHECK='TRUE';
      NO_DIR_CHECK='TRUE';
      ALLOW_CONNECT='TRUE';
    'SW2':
      PIN_NUMBER='(11)';
      OUTPUT_LOAD='(1.0,-1.0)';
      PINUSE='OUT';
    'TRK_REF':
      PIN_NUMBER='(8)';
      INPUT_LOAD='(-0.01,0.01)';
      PINUSE='IN';
    'MODE':
      PIN_NUMBER='(12)';
      INPUT_LOAD='(-0.01,0.01)';
      PINUSE='IN';
    'CS':
      PIN_NUMBER='(4)';
      INPUT_LOAD='(-0.01,0.01)';
      PINUSE='IN';
    'SW1':
      PIN_NUMBER='(2)';
      OUTPUT_LOAD='(1.0,-1.0)';
      PINUSE='OUT';
  end_pin;
  body
      PART_NAME='MPQ8626GDZ';
      BODY_NAME='MPQ8626GDZ';
      PHYS_DES_PREFIX='U';
      CLASS='IC';
      STANDARD='';
      LIFECYCLE='';
      JEDEC_TYPE='QFN14_0-5_3X2XA';
      DESCRIPTION='IC CTRL(14P)MPQ8626GD-Z(QFN)';
      MANUFTR='MPS';
      MANUF_PN='MPQ8626GD-Z';
      RD_CMPLS_LVL='EP(V1)';
      CMPLS_LVL='';
      FROM_PJ='F09A-BEN';
      DIP_SMD='';
      DATA='MPS_MPQ8626GD-Z.pdf';
      EE_CHECK_LIST='';
      FP_ECN='';
      PSL='';
      CREATOR='';
      STATUS='';
      MSD='NA';
      ESD_CDM='NA';
      ESD_HBM='NA';
      ESD_MM='NA';
      PIN_LENGTH_SHORT_PIN='0 MILS';
      PIN_LENGTH_LONG_PIN='0 MILS';
      CREATEDAY='20171225';
      PARENT_PART_TYPE='MPQ8626GDZ';
      PARENT_PPT='MPQ8626GDZ';
      PARENT_PPT_PART='MPQ8626GDZ-MPQ8626GD-Z,SMLF,IC,AL008626000';
  end_body;
end_primitive;
primitive 'MPQ8633AGLEC807Z-MPQ8633AGLE-CA';
  pin
    'VIN1':
      PIN_NUMBER='(10)';
      INPUT_LOAD='(-0.01,0.01)';
      PINUSE='IN';
    'PGOOD':
      PIN_NUMBER='(9)';
      OUTPUT_LOAD='(1.0,-1.0)';
      PINUSE='OUT';
    'PGND':
      PIN_NUMBER='(11_18)';
      PINUSE='POWER';
      NO_LOAD_CHECK='Both';
      NO_IO_CHECK='Both';
      NO_ASSERT_CHECK='TRUE';
      NO_DIR_CHECK='TRUE';
      ALLOW_CONNECT='TRUE';
    'EN':
      PIN_NUMBER='(8)';
      INPUT_LOAD='(-0.01,0.01)';
      PINUSE='IN';
    'BST':
      PIN_NUMBER='(1)';
      INPUT_LOAD='(-0.01,0.01)';
      PINUSE='IN';
    'FB':
      PIN_NUMBER='(7)';
      INPUT_LOAD='(-0.01,0.01)';
      PINUSE='IN';
    'AGND':
      PIN_NUMBER='(2)';
      PINUSE='POWER';
      NO_LOAD_CHECK='Both';
      NO_IO_CHECK='Both';
      NO_ASSERT_CHECK='TRUE';
      NO_DIR_CHECK='TRUE';
      ALLOW_CONNECT='TRUE';
    'VCC':
      PIN_NUMBER='(19)';
      PINUSE='POWER';
      NO_LOAD_CHECK='Both';
      NO_IO_CHECK='Both';
      NO_ASSERT_CHECK='TRUE';
      NO_DIR_CHECK='TRUE';
      ALLOW_CONNECT='TRUE';
    'RGND':
      PIN_NUMBER='(6)';
      PINUSE='POWER';
      NO_LOAD_CHECK='Both';
      NO_IO_CHECK='Both';
      NO_ASSERT_CHECK='TRUE';
      NO_DIR_CHECK='TRUE';
      ALLOW_CONNECT='TRUE';
    'SW':
      PIN_NUMBER='(20)';
      OUTPUT_LOAD='(1.0,-1.0)';
      PINUSE='OUT';
    'TRK_REF':
      PIN_NUMBER='(5)';
      INPUT_LOAD='(-0.01,0.01)';
      PINUSE='IN';
    'MODE':
      PIN_NUMBER='(4)';
      INPUT_LOAD='(-0.01,0.01)';
      PINUSE='IN';
    'CS':
      PIN_NUMBER='(3)';
      INPUT_LOAD='(-0.01,0.01)';
      PINUSE='IN';
    'VIN2':
      PIN_NUMBER='(21)';
      INPUT_LOAD='(-0.01,0.01)';
      PINUSE='IN';
  end_pin;
  body
      PART_NAME='MPQ8633AGLEC807Z';
      BODY_NAME='MPQ8633AGLEC807Z';
      PHYS_DES_PREFIX='U';
      CLASS='IC';
      STANDARD='';
      LIFECYCLE='';
      JEDEC_TYPE='QFN14_4X3';
      DESCRIPTION='IC CTRL(21P)MPQ8633AGLE-C807-Z(QFN)';
      MANUFTR='MPS';
      MANUF_PN='MPQ8633AGLE-C807-Z';
      RD_CMPLS_LVL='EP(V1)';
      CMPLS_LVL='';
      FROM_PJ='F0B-HANK';
      DIP_SMD='';
      DATA='MPS_MPQ8633AGLE-C807-Z.pdf';
      EE_CHECK_LIST='';
      FP_ECN='';
      PSL='';
      CREATOR='';
      STATUS='';
      MSD='Level-2';
      ESD_CDM='0';
      ESD_HBM='0';
      ESD_MM='00';
      PIN_LENGTH_SHORT_PIN='0 MILS';
      PIN_LENGTH_LONG_PIN='0 MILS';
      CREATEDAY='20180613';
      PARENT_PART_TYPE='MPQ8633AGLEC807Z';
      PARENT_PPT='MPQ8633AGLEC807Z';
      PARENT_PPT_PART='MPQ8633AGLEC807Z-MPQ8633AGLE-C807-Z,SMLF,IC,AL008633007';
  end_body;
end_primitive;
primitive 'MX25L51245GMI10G-MX25L51245GMIA';
  pin
    'NC_SIO3':
      PIN_NUMBER='(1)';
      BIDIRECTIONAL='TRUE';
      INPUT_LOAD='(-0.01,0.01)';
      OUTPUT_LOAD='(1.0,-1.0)';
      PINUSE='BI';
    'VCC':
      PIN_NUMBER='(2)';
      PINUSE='POWER';
      NO_LOAD_CHECK='Both';
      NO_IO_CHECK='Both';
      NO_ASSERT_CHECK='TRUE';
      NO_DIR_CHECK='TRUE';
      ALLOW_CONNECT='TRUE';
    'RESET#':
      PIN_NUMBER='(3)';
      BIDIRECTIONAL='TRUE';
      INPUT_LOAD='(-0.01,0.01)';
      OUTPUT_LOAD='(1.0,-1.0)';
      PINUSE='BI';
    'NC1':
      PIN_NUMBER='(4)';
      OUTPUT_TYPE='(TS,TS)';
      INPUT_LOAD='(-0.01,0.01)';
      OUTPUT_LOAD='(1.0,-1.0)';
      PINUSE='TRI';
    'DNU1':
      PIN_NUMBER='(5)';
      OUTPUT_TYPE='(TS,TS)';
      INPUT_LOAD='(-0.01,0.01)';
      OUTPUT_LOAD='(1.0,-1.0)';
      PINUSE='TRI';
    'DNU2':
      PIN_NUMBER='(6)';
      OUTPUT_TYPE='(TS,TS)';
      INPUT_LOAD='(-0.01,0.01)';
      OUTPUT_LOAD='(1.0,-1.0)';
      PINUSE='TRI';
    'CS#':
      PIN_NUMBER='(7)';
      BIDIRECTIONAL='TRUE';
      INPUT_LOAD='(-0.01,0.01)';
      OUTPUT_LOAD='(1.0,-1.0)';
      PINUSE='BI';
    'SO_SIO1':
      PIN_NUMBER='(8)';
      BIDIRECTIONAL='TRUE';
      INPUT_LOAD='(-0.01,0.01)';
      OUTPUT_LOAD='(1.0,-1.0)';
      PINUSE='BI';
    'WP#_SIO2':
      PIN_NUMBER='(9)';
      BIDIRECTIONAL='TRUE';
      INPUT_LOAD='(-0.01,0.01)';
      OUTPUT_LOAD='(1.0,-1.0)';
      PINUSE='BI';
    'GND':
      PIN_NUMBER='(10)';
      PINUSE='POWER';
      NO_LOAD_CHECK='Both';
      NO_IO_CHECK='Both';
      NO_ASSERT_CHECK='TRUE';
      NO_DIR_CHECK='TRUE';
      ALLOW_CONNECT='TRUE';
    'DNU3':
      PIN_NUMBER='(11)';
      OUTPUT_TYPE='(TS,TS)';
      INPUT_LOAD='(-0.01,0.01)';
      OUTPUT_LOAD='(1.0,-1.0)';
      PINUSE='TRI';
    'DNU4':
      PIN_NUMBER='(12)';
      OUTPUT_TYPE='(TS,TS)';
      INPUT_LOAD='(-0.01,0.01)';
      OUTPUT_LOAD='(1.0,-1.0)';
      PINUSE='TRI';
    'NC2':
      PIN_NUMBER='(13)';
      OUTPUT_TYPE='(TS,TS)';
      INPUT_LOAD='(-0.01,0.01)';
      OUTPUT_LOAD='(1.0,-1.0)';
      PINUSE='TRI';
    'NC3':
      PIN_NUMBER='(14)';
      OUTPUT_TYPE='(TS,TS)';
      INPUT_LOAD='(-0.01,0.01)';
      OUTPUT_LOAD='(1.0,-1.0)';
      PINUSE='TRI';
    'SI_SIO0':
      PIN_NUMBER='(15)';
      BIDIRECTIONAL='TRUE';
      INPUT_LOAD='(-0.01,0.01)';
      OUTPUT_LOAD='(1.0,-1.0)';
      PINUSE='BI';
    'SCLK':
      PIN_NUMBER='(16)';
      INPUT_LOAD='(-0.01,0.01)';
      PINUSE='IN';
  end_pin;
  body
      PART_NAME='MX25L51245GMI10G';
      BODY_NAME='MX25L51245GMI10G';
      PHYS_DES_PREFIX='U';
      CLASS='IC';
      STANDARD='End of Design';
      LIFECYCLE='Comp-Approve';
      JEDEC_TYPE='SOP16_1-27_10-3X7-52';
      DESCRIPTION='IC FLASH(16P)MX25L51245GMI-10G(SOP)';
      MANUFTR='MAX';
      MANUF_PN='MX25L51245GMI-10G';
      RD_CMPLS_LVL='EP(V1)';
      CMPLS_LVL='EP(V1)';
      FROM_PJ='S3C-SEB';
      DIP_SMD='';
      DATA='MAX_MX25L51245GMI-10G.pdf';
      EE_CHECK_LIST='';
      FP_ECN='';
      PSL='';
      CREATOR='';
      STATUS='';
      MSD='NA';
      ESD_CDM='NA';
      ESD_HBM='NA';
      ESD_MM='NA';
      PIN_LENGTH_SHORT_PIN='0 MILS';
      PIN_LENGTH_LONG_PIN='0 MILS';
      CREATEDAY='20171211';
      PARENT_PART_TYPE='MX25L51245GMI10G';
      PARENT_PPT='MX25L51245GMI10G';
      PARENT_PPT_PART='MX25L51245GMI10G-MX25L51245GMI-10G,SMLF,EMPTY,AKE3FF00Z00';
  end_body;
end_primitive;
primitive 'NB695GDZ-NB695GD-Z,SMLF,IC,AL0A';
  pin
    'VIN':
      PIN_NUMBER='(1)';
      PINUSE='POWER';
      NO_LOAD_CHECK='Both';
      NO_IO_CHECK='Both';
      NO_ASSERT_CHECK='TRUE';
      NO_DIR_CHECK='TRUE';
      ALLOW_CONNECT='TRUE';
    'PG':
      PIN_NUMBER='(13)';
      OUTPUT_LOAD='(1.0,-1.0)';
      PINUSE='OUT';
    'PGND':
      PIN_NUMBER='(2)';
      PINUSE='POWER';
      NO_LOAD_CHECK='Both';
      NO_IO_CHECK='Both';
      NO_ASSERT_CHECK='TRUE';
      NO_DIR_CHECK='TRUE';
      ALLOW_CONNECT='TRUE';
    'EN':
      PIN_NUMBER='(5)';
      INPUT_LOAD='(-0.01,0.01)';
      PINUSE='IN';
    'BST':
      PIN_NUMBER='(9)';
      PINUSE='POWER';
      NO_LOAD_CHECK='Both';
      NO_IO_CHECK='Both';
      NO_ASSERT_CHECK='TRUE';
      NO_DIR_CHECK='TRUE';
      ALLOW_CONNECT='TRUE';
    'AGND':
      PIN_NUMBER='(11)';
      PINUSE='POWER';
      NO_LOAD_CHECK='Both';
      NO_IO_CHECK='Both';
      NO_ASSERT_CHECK='TRUE';
      NO_DIR_CHECK='TRUE';
      ALLOW_CONNECT='TRUE';
    'LP#':
      PIN_NUMBER='(6)';
      INPUT_LOAD='(-0.01,0.01)';
      PINUSE='IN';
    'C1':
      PIN_NUMBER='(3)';
      INPUT_LOAD='(-0.01,0.01)';
      PINUSE='IN';
    'C0':
      PIN_NUMBER='(4)';
      INPUT_LOAD='(-0.01,0.01)';
      PINUSE='IN';
    'MODE':
      PIN_NUMBER='(7)';
      INPUT_LOAD='(-0.01,0.01)';
      PINUSE='IN';
    'VOUT':
      PIN_NUMBER='(12)';
      PINUSE='POWER';
      NO_LOAD_CHECK='Both';
      NO_IO_CHECK='Both';
      NO_ASSERT_CHECK='TRUE';
      NO_DIR_CHECK='TRUE';
      ALLOW_CONNECT='TRUE';
    'SW':
      PIN_NUMBER='(8)';
      PINUSE='POWER';
      NO_LOAD_CHECK='Both';
      NO_IO_CHECK='Both';
      NO_ASSERT_CHECK='TRUE';
      NO_DIR_CHECK='TRUE';
      ALLOW_CONNECT='TRUE';
    '3V3':
      PIN_NUMBER='(10)';
      PINUSE='POWER';
      NO_LOAD_CHECK='Both';
      NO_IO_CHECK='Both';
      NO_ASSERT_CHECK='TRUE';
      NO_DIR_CHECK='TRUE';
      ALLOW_CONNECT='TRUE';
  end_pin;
  body
      PART_NAME='NB695GDZ';
      BODY_NAME='NB695GDZ';
      PHYS_DES_PREFIX='U';
      CLASS='IC';
      STANDARD='';
      LIFECYCLE='';
      JEDEC_TYPE='QFN13_2X3';
      DESCRIPTION='IC CTRL(13P)NB695GD-Z(QFN-13)';
      MANUFTR='MPS';
      MANUF_PN='NB695GD-Z';
      RD_CMPLS_LVL='EP(V1)';
      CMPLS_LVL='EP(V1)';
      FROM_PJ='S6L-MARK';
      DIP_SMD='';
      DATA='MPS_NB695GD-Z.pdf';
      EE_CHECK_LIST='';
      FP_ECN='';
      PSL='';
      CREATOR='';
      STATUS='';
      MSD='NA';
      ESD_CDM='N/A';
      ESD_HBM='N/A';
      ESD_MM='N/A';
      PIN_LENGTH_SHORT_PIN='0 MILS';
      PIN_LENGTH_LONG_PIN='0 MILS';
      CREATEDAY='20190314';
      PARENT_PART_TYPE='NB695GDZ';
      PARENT_PPT='NB695GDZ';
      PARENT_PPT_PART='NB695GDZ-NB695GD-Z,SMLF,IC,AL000695001';
  end_body;
end_primitive;
primitive 'NC7SB3157_SMLF-NC7SB3157P6X,NCA';
  pin
    'B1':
      PIN_NUMBER='(1)';
      INPUT_LOAD='(-0.01,0.01)';
      OUTPUT_LOAD='(1.0,-1.0)';
      BIDIRECTIONAL='TRUE';
      PINUSE='BI';
    'GND':
      PIN_NUMBER='(2)';
      PINUSE='POWER';
    'B0':
      PIN_NUMBER='(3)';
      INPUT_LOAD='(-0.01,0.01)';
      OUTPUT_LOAD='(1.0,-1.0)';
      BIDIRECTIONAL='TRUE';
      PINUSE='BI';
    'S':
      PIN_NUMBER='(6)';
      INPUT_LOAD='(-0.01,0.01)';
      PINUSE='IN';
    'VCC':
      PIN_NUMBER='(5)';
      PINUSE='POWER';
    'A':
      PIN_NUMBER='(4)';
      INPUT_LOAD='(-0.01,0.01)';
      OUTPUT_LOAD='(1.0,-1.0)';
      BIDIRECTIONAL='TRUE';
      PINUSE='BI';
  end_pin;
  body
      PHYS_DES_PREFIX='U';
      CLASS='IC';
      PART_NAME='NC7SB3157';
      BODY_NAME='NC7SB3157';
      STANDARD='End of Design';
      LIFECYCLE='Comp-Approve';
      ENVCOMP='YES';
      JEDEC_TYPE='SC70-6';
      DESCRIPTION='IC(6P) NC7SB3157P6X(SC70-6)';
      HEIGHT='.044IN';
      COMPONENT_TYPE='SMALLSMT';
      LEAD_LENGTH='';
      LPID='';
      DAY='20100709';
      PARENT_PART_TYPE='NC7SB3157';
      PARENT_PPT='NC7SB3157';
      PARENT_PPT_PART='NC7SB3157_SMLF-NC7SB3157P6X,NC7SB3157P6X,IC,ALSB3157000';
  end_body;
end_primitive;
primitive 'NCP380HSNAJAAT1G-NCP380HSNAJAAA';
  pin
    'FLAG_N':
      PIN_NUMBER='(4)';
      OUTPUT_LOAD='(1.0,-1.0)';
      PINUSE='OUT';
    'IN':
      PIN_NUMBER='(1)';
      PINUSE='POWER';
      NO_LOAD_CHECK='Both';
      NO_IO_CHECK='Both';
      NO_ASSERT_CHECK='TRUE';
      NO_DIR_CHECK='TRUE';
      ALLOW_CONNECT='TRUE';
    'ILIM':
      PIN_NUMBER='(5)';
      INPUT_LOAD='(-0.01,0.01)';
      PINUSE='IN';
    'OUT':
      PIN_NUMBER='(6)';
      OUTPUT_LOAD='(1.0,-1.0)';
      PINUSE='OUT';
    'EN':
      PIN_NUMBER='(3)';
      INPUT_LOAD='(-0.01,0.01)';
      PINUSE='IN';
    'GND':
      PIN_NUMBER='(2)';
      PINUSE='POWER';
      NO_LOAD_CHECK='Both';
      NO_IO_CHECK='Both';
      NO_ASSERT_CHECK='TRUE';
      NO_DIR_CHECK='TRUE';
      ALLOW_CONNECT='TRUE';
  end_pin;
  body
      PART_NAME='NCP380HSNAJAAT1G';
      BODY_NAME='NCP380HSNAJAAT1G';
      PHYS_DES_PREFIX='U';
      CLASS='IC';
      STANDARD='';
      LIFECYCLE='';
      JEDEC_TYPE='TSOP6XE';
      DESCRIPTION='IC OTHER(6P)NCP380HSNAJAAT1G(TSOP-6)';
      MANUFTR='ONS';
      MANUF_PN='NCP380HSNAJAAT1G';
      RD_CMPLS_LVL='EP(V1)';
      CMPLS_LVL='EP(V1)';
      FROM_PJ='F0C-IVES';
      DIP_SMD='';
      DATA='ONS_NCP380HSNAJAAT1G.pdf';
      EE_CHECK_LIST='';
      FP_ECN='';
      PSL='';
      CREATOR='';
      STATUS='';
      MSD='';
      ESD_CDM='';
      ESD_HBM='';
      ESD_MM='';
      PIN_LENGTH_SHORT_PIN='0 MILS';
      PIN_LENGTH_LONG_PIN='0 MILS';
      CREATEDAY='20210616';
      PARENT_PART_TYPE='NCP380HSNAJAAT1G';
      PARENT_PPT='NCP380HSNAJAAT1G';
      PARENT_PPT_PART='NCP380HSNAJAAT1G-NCP380HSNAJAAT1G,SMLF,IC,AL000380K00';
  end_body;
end_primitive;
primitive 'OSC4_7X25000018-25MHZ,SMLF,MISA';
  pin
    'OE':
      PIN_NUMBER='(1)';
      INPUT_LOAD='(-0.01,0.01)';
      PINUSE='IN';
    'GND':
      PIN_NUMBER='(2)';
      PINUSE='POWER';
      NO_LOAD_CHECK='Both';
      NO_IO_CHECK='Both';
      NO_ASSERT_CHECK='TRUE';
      NO_DIR_CHECK='TRUE';
      ALLOW_CONNECT='TRUE';
    'OUT':
      PIN_NUMBER='(3)';
      OUTPUT_LOAD='(1.0,-1.0)';
      PINUSE='OUT';
    'VDD':
      PIN_NUMBER='(4)';
      PINUSE='POWER';
      NO_LOAD_CHECK='Both';
      NO_IO_CHECK='Both';
      NO_ASSERT_CHECK='TRUE';
      NO_DIR_CHECK='TRUE';
      ALLOW_CONNECT='TRUE';
  end_pin;
  body
      PART_NAME='OSC4_7X25000018';
      BODY_NAME='OSC4_7X25000018';
      PHYS_DES_PREFIX='OSC';
      CLASS='IO';
      STANDARD='';
      LIFECYCLE='';
      JEDEC_TYPE='X_7X';
      ALT_SYMBOLS='';
      DESCRIPTION='OSC SMD 25MHZ(+-25PPM,3.3V)7X25000018';
      MANUFTR='TXC';
      MANUF_PN='7X25000018';
      RD_CMPLS_LVL='EP(V1)';
      CMPLS_LVL='EP(V1)';
      DIP_SMD='';
      FROM_PJ='T2R-GAVEN';
      DATA='TXC_7X25000018_revA3.pdf';
      FP_ECN='';
      EE_CHECK_LIST='';
      STATUS='';
      PSL='';
      PREFERENCE='';
      CREATOR='';
      CREATEDAY='20140704';
      PARENT_PART_TYPE='OSC4_7X25000018';
      PARENT_PPT='OSC4_7X25000018';
      PARENT_PPT_PART='OSC4_7X25000018-25MHZ,SMLF,MISC,BF625000023';
  end_body;
end_primitive;
primitive 'PCA9517ADP_SMLF-PCA9517ADP,IC,A';
  pin
    'ENABLE':
      PIN_NUMBER='(5)';
      INPUT_LOAD='(-0.01,0.01)';
      OUTPUT_LOAD='(1.0,-1.0)';
      BIDIRECTIONAL='TRUE';
      PINUSE='BI';
    'VCCB':
      PIN_NUMBER='(8)';
      INPUT_LOAD='(-0.01,0.01)';
      OUTPUT_LOAD='(1.0,-1.0)';
      BIDIRECTIONAL='TRUE';
      PINUSE='BI';
    'SCLA':
      PIN_NUMBER='(2)';
      INPUT_LOAD='(-0.01,0.01)';
      OUTPUT_LOAD='(1.0,-1.0)';
      BIDIRECTIONAL='TRUE';
      PINUSE='BI';
    'SDAA':
      PIN_NUMBER='(3)';
      INPUT_LOAD='(-0.01,0.01)';
      OUTPUT_LOAD='(1.0,-1.0)';
      BIDIRECTIONAL='TRUE';
      PINUSE='BI';
    'SDAB':
      PIN_NUMBER='(6)';
      INPUT_LOAD='(-0.01,0.01)';
      OUTPUT_LOAD='(1.0,-1.0)';
      BIDIRECTIONAL='TRUE';
      PINUSE='BI';
    'SCLB':
      PIN_NUMBER='(7)';
      INPUT_LOAD='(-0.01,0.01)';
      OUTPUT_LOAD='(1.0,-1.0)';
      BIDIRECTIONAL='TRUE';
      PINUSE='BI';
    'VCCA':
      PIN_NUMBER='(1)';
      PINUSE='POWER';
    'GND':
      PIN_NUMBER='(4)';
      PINUSE='POWER';
  end_pin;
  body
      CLASS='IC';
      PART_NAME='PCA9517ADP';
      PHYS_DES_PREFIX='D';
      STANDARD='';
      LIFECYCLE='';
      JEDEC_TYPE='TSSOP8_3';
      DESCRIPTION='IC OTHER (8P) PCA9517ADP(TSSOP8)';
      HEIGHT='.044IN';
      COMPONENT_TYPE='SMALLSMT';
      LEAD_LENGTH='';
      DFM_EXCLUSION='';
      DAY='20101012';
      PARENT_PART_TYPE='PCA9517ADP';
      PARENT_PPT='PCA9517ADP';
      PARENT_PPT_PART='PCA9517ADP_SMLF-PCA9517ADP,IC,AL009517K00';
  end_body;
end_primitive;
primitive 'PCA9555PW_SMLF-PCA9555PW,IC,TMA';
  pin
    'INT*':
      PIN_NUMBER='(1)';
      OUTPUT_LOAD='(1.0,-1.0)';
      PINUSE='OUT';
    'SDA':
      PIN_NUMBER='(23)';
      INPUT_LOAD='(-0.01,0.01)';
      OUTPUT_LOAD='(1.0,-1.0)';
      BIDIRECTIONAL='TRUE';
      PINUSE='BI';
    'SCL':
      PIN_NUMBER='(22)';
      INPUT_LOAD='(-0.01,0.01)';
      OUTPUT_LOAD='(1.0,-1.0)';
      BIDIRECTIONAL='TRUE';
      PINUSE='BI';
    'P00':
      PIN_NUMBER='(4)';
      INPUT_LOAD='(-0.01,0.01)';
      OUTPUT_LOAD='(1.0,-1.0)';
      BIDIRECTIONAL='TRUE';
      PINUSE='BI';
    'P01':
      PIN_NUMBER='(5)';
      INPUT_LOAD='(-0.01,0.01)';
      OUTPUT_LOAD='(1.0,-1.0)';
      BIDIRECTIONAL='TRUE';
      PINUSE='BI';
    'P02':
      PIN_NUMBER='(6)';
      INPUT_LOAD='(-0.01,0.01)';
      OUTPUT_LOAD='(1.0,-1.0)';
      BIDIRECTIONAL='TRUE';
      PINUSE='BI';
    'P03':
      PIN_NUMBER='(7)';
      INPUT_LOAD='(-0.01,0.01)';
      OUTPUT_LOAD='(1.0,-1.0)';
      BIDIRECTIONAL='TRUE';
      PINUSE='BI';
    'P04':
      PIN_NUMBER='(8)';
      INPUT_LOAD='(-0.01,0.01)';
      OUTPUT_LOAD='(1.0,-1.0)';
      BIDIRECTIONAL='TRUE';
      PINUSE='BI';
    'P05':
      PIN_NUMBER='(9)';
      INPUT_LOAD='(-0.01,0.01)';
      OUTPUT_LOAD='(1.0,-1.0)';
      BIDIRECTIONAL='TRUE';
      PINUSE='BI';
    'P06':
      PIN_NUMBER='(10)';
      INPUT_LOAD='(-0.01,0.01)';
      OUTPUT_LOAD='(1.0,-1.0)';
      BIDIRECTIONAL='TRUE';
      PINUSE='BI';
    'P07':
      PIN_NUMBER='(11)';
      INPUT_LOAD='(-0.01,0.01)';
      OUTPUT_LOAD='(1.0,-1.0)';
      BIDIRECTIONAL='TRUE';
      PINUSE='BI';
    'P10':
      PIN_NUMBER='(13)';
      INPUT_LOAD='(-0.01,0.01)';
      OUTPUT_LOAD='(1.0,-1.0)';
      BIDIRECTIONAL='TRUE';
      PINUSE='BI';
    'P11':
      PIN_NUMBER='(14)';
      INPUT_LOAD='(-0.01,0.01)';
      OUTPUT_LOAD='(1.0,-1.0)';
      BIDIRECTIONAL='TRUE';
      PINUSE='BI';
    'P12':
      PIN_NUMBER='(15)';
      INPUT_LOAD='(-0.01,0.01)';
      OUTPUT_LOAD='(1.0,-1.0)';
      BIDIRECTIONAL='TRUE';
      PINUSE='BI';
    'P13':
      PIN_NUMBER='(16)';
      INPUT_LOAD='(-0.01,0.01)';
      OUTPUT_LOAD='(1.0,-1.0)';
      BIDIRECTIONAL='TRUE';
      PINUSE='BI';
    'P14':
      PIN_NUMBER='(17)';
      INPUT_LOAD='(-0.01,0.01)';
      OUTPUT_LOAD='(1.0,-1.0)';
      BIDIRECTIONAL='TRUE';
      PINUSE='BI';
    'P15':
      PIN_NUMBER='(18)';
      INPUT_LOAD='(-0.01,0.01)';
      OUTPUT_LOAD='(1.0,-1.0)';
      BIDIRECTIONAL='TRUE';
      PINUSE='BI';
    'P16':
      PIN_NUMBER='(19)';
      INPUT_LOAD='(-0.01,0.01)';
      OUTPUT_LOAD='(1.0,-1.0)';
      BIDIRECTIONAL='TRUE';
      PINUSE='BI';
    'P17':
      PIN_NUMBER='(20)';
      INPUT_LOAD='(-0.01,0.01)';
      OUTPUT_LOAD='(1.0,-1.0)';
      BIDIRECTIONAL='TRUE';
      PINUSE='BI';
    'A0':
      PIN_NUMBER='(21)';
      INPUT_LOAD='(-0.01,0.01)';
      OUTPUT_LOAD='(1.0,-1.0)';
      BIDIRECTIONAL='TRUE';
      PINUSE='BI';
    'A1':
      PIN_NUMBER='(2)';
      INPUT_LOAD='(-0.01,0.01)';
      OUTPUT_LOAD='(1.0,-1.0)';
      BIDIRECTIONAL='TRUE';
      PINUSE='BI';
    'A2':
      PIN_NUMBER='(3)';
      INPUT_LOAD='(-0.01,0.01)';
      OUTPUT_LOAD='(1.0,-1.0)';
      BIDIRECTIONAL='TRUE';
      PINUSE='BI';
    'VDD':
      PIN_NUMBER='(24)';
      PINUSE='POWER';
    'VSS':
      PIN_NUMBER='(12)';
      PINUSE='POWER';
  end_pin;
  body
      CLASS='IC';
      PART_NAME='PCA9555PW';
      PHYS_DES_PREFIX='U';
      JEDEC_TYPE='TSSOP24';
      STANDARD='';
      LIFECYCLE='';
      DESCRIPTION='IC(24P) PCA9555PW(TSSOP)EP';
      HEIGHT='.044IN';
      COMPONENT_TYPE='SMALLSMT';
      LEAD_LENGTH='';
      DFM_EXCLUSION='';
      PARENT_PART_TYPE='PCA9555PW';
      PARENT_PPT='PCA9555PW';
      PARENT_PPT_PART='PCA9555PW_SMLF-PCA9555PW,IC,TMP_QAL009555K04';
  end_body;
end_primitive;
primitive 'PI3PCIE3212ZBEX-PI3PCIE3212ZBEA';
  pin
    'VDD2':
      PIN_NUMBER='(10)';
      PINUSE='POWER';
      NO_LOAD_CHECK='Both';
      NO_IO_CHECK='Both';
      NO_ASSERT_CHECK='TRUE';
      NO_DIR_CHECK='TRUE';
      ALLOW_CONNECT='TRUE';
    'VDD1':
      PIN_NUMBER='(6)';
      PINUSE='POWER';
      NO_LOAD_CHECK='Both';
      NO_IO_CHECK='Both';
      NO_ASSERT_CHECK='TRUE';
      NO_DIR_CHECK='TRUE';
      ALLOW_CONNECT='TRUE';
    'VDD0':
      PIN_NUMBER='(1)';
      PINUSE='POWER';
      NO_LOAD_CHECK='Both';
      NO_IO_CHECK='Both';
      NO_ASSERT_CHECK='TRUE';
      NO_DIR_CHECK='TRUE';
      ALLOW_CONNECT='TRUE';
    'A0_P':
      PIN_NUMBER='(3)';
      BIDIRECTIONAL='TRUE';
      INPUT_LOAD='(-0.01,0.01)';
      OUTPUT_LOAD='(1.0,-1.0)';
      PINUSE='BI';
    'A0_N':
      PIN_NUMBER='(4)';
      BIDIRECTIONAL='TRUE';
      INPUT_LOAD='(-0.01,0.01)';
      OUTPUT_LOAD='(1.0,-1.0)';
      PINUSE='BI';
    'A1_P':
      PIN_NUMBER='(7)';
      BIDIRECTIONAL='TRUE';
      INPUT_LOAD='(-0.01,0.01)';
      OUTPUT_LOAD='(1.0,-1.0)';
      PINUSE='BI';
    'A1_N':
      PIN_NUMBER='(8)';
      BIDIRECTIONAL='TRUE';
      INPUT_LOAD='(-0.01,0.01)';
      OUTPUT_LOAD='(1.0,-1.0)';
      PINUSE='BI';
    'SEL':
      PIN_NUMBER='(9)';
      INPUT_LOAD='(-0.01,0.01)';
      PINUSE='IN';
    'B0_P':
      PIN_NUMBER='(19)';
      BIDIRECTIONAL='TRUE';
      INPUT_LOAD='(-0.01,0.01)';
      OUTPUT_LOAD='(1.0,-1.0)';
      PINUSE='BI';
    'B0_N':
      PIN_NUMBER='(18)';
      BIDIRECTIONAL='TRUE';
      INPUT_LOAD='(-0.01,0.01)';
      OUTPUT_LOAD='(1.0,-1.0)';
      PINUSE='BI';
    'B1_P':
      PIN_NUMBER='(17)';
      BIDIRECTIONAL='TRUE';
      INPUT_LOAD='(-0.01,0.01)';
      OUTPUT_LOAD='(1.0,-1.0)';
      PINUSE='BI';
    'B1_N':
      PIN_NUMBER='(16)';
      BIDIRECTIONAL='TRUE';
      INPUT_LOAD='(-0.01,0.01)';
      OUTPUT_LOAD='(1.0,-1.0)';
      PINUSE='BI';
    'C0_P':
      PIN_NUMBER='(15)';
      BIDIRECTIONAL='TRUE';
      INPUT_LOAD='(-0.01,0.01)';
      OUTPUT_LOAD='(1.0,-1.0)';
      PINUSE='BI';
    'C0_N':
      PIN_NUMBER='(14)';
      BIDIRECTIONAL='TRUE';
      INPUT_LOAD='(-0.01,0.01)';
      OUTPUT_LOAD='(1.0,-1.0)';
      PINUSE='BI';
    'C1_P':
      PIN_NUMBER='(13)';
      BIDIRECTIONAL='TRUE';
      INPUT_LOAD='(-0.01,0.01)';
      OUTPUT_LOAD='(1.0,-1.0)';
      PINUSE='BI';
    'C1_N':
      PIN_NUMBER='(12)';
      BIDIRECTIONAL='TRUE';
      INPUT_LOAD='(-0.01,0.01)';
      OUTPUT_LOAD='(1.0,-1.0)';
      PINUSE='BI';
    'TH':
      PIN_NUMBER='(TH)';
      PINUSE='POWER';
      NO_LOAD_CHECK='Both';
      NO_IO_CHECK='Both';
      NO_ASSERT_CHECK='TRUE';
      NO_DIR_CHECK='TRUE';
      ALLOW_CONNECT='TRUE';
    'GND2':
      PIN_NUMBER='(11)';
      PINUSE='POWER';
      NO_LOAD_CHECK='Both';
      NO_IO_CHECK='Both';
      NO_ASSERT_CHECK='TRUE';
      NO_DIR_CHECK='TRUE';
      ALLOW_CONNECT='TRUE';
    'GND1':
      PIN_NUMBER='(5)';
      PINUSE='POWER';
      NO_LOAD_CHECK='Both';
      NO_IO_CHECK='Both';
      NO_ASSERT_CHECK='TRUE';
      NO_DIR_CHECK='TRUE';
      ALLOW_CONNECT='TRUE';
    'GND0':
      PIN_NUMBER='(20)';
      PINUSE='POWER';
      NO_LOAD_CHECK='Both';
      NO_IO_CHECK='Both';
      NO_ASSERT_CHECK='TRUE';
      NO_DIR_CHECK='TRUE';
      ALLOW_CONNECT='TRUE';
    'PD':
      PIN_NUMBER='(2)';
      INPUT_LOAD='(-0.01,0.01)';
      PINUSE='IN';
  end_pin;
  body
      PART_NAME='PI3PCIE3212ZBEX';
      BODY_NAME='PI3PCIE3212ZBEX';
      PHYS_DES_PREFIX='U';
      CLASS='IC';
      STANDARD='';
      LIFECYCLE='';
      JEDEC_TYPE='QFN20_TH_0-5_2-5X4-5';
      DESCRIPTION='IC OTHER(20P) PI3PCIE3212ZBEX(QFN)';
      MANUFTR='PIM';
      MANUF_PN='PI3PCIE3212ZBEX';
      RD_CMPLS_LVL='EP(V1)';
      CMPLS_LVL='EP(V1)';
      FROM_PJ='IX5-PATRICK';
      DIP_SMD='';
      DATA='PIM_PI3PCIE3212ZBX.pdf';
      EE_CHECK_LIST='';
      FP_ECN='';
      PSL='';
      CREATOR='';
      STATUS='';
      CREATEDAY='20160201';
      PARENT_PART_TYPE='PI3PCIE3212ZBEX';
      PARENT_PPT='PI3PCIE3212ZBEX';
      PARENT_PPT_PART='PI3PCIE3212ZBEX-PI3PCIE3212ZBEX,SMLF,IC,AL003212003';
  end_body;
end_primitive;
primitive 'PICOPROBE_BXA-DELTA-L 4.0,SMLFA';
  pin
    '2_N':
      PIN_NUMBER='(2)';
      PINUSE='POWER';
      NO_LOAD_CHECK='Both';
      NO_IO_CHECK='Both';
      NO_ASSERT_CHECK='TRUE';
      NO_DIR_CHECK='TRUE';
      ALLOW_CONNECT='TRUE';
    '3_G':
      PIN_NUMBER='(3)';
      PINUSE='POWER';
      NO_LOAD_CHECK='Both';
      NO_IO_CHECK='Both';
      NO_ASSERT_CHECK='TRUE';
      NO_DIR_CHECK='TRUE';
      ALLOW_CONNECT='TRUE';
    '1_P':
      PIN_NUMBER='(1)';
      PINUSE='POWER';
      NO_LOAD_CHECK='Both';
      NO_IO_CHECK='Both';
      NO_ASSERT_CHECK='TRUE';
      NO_DIR_CHECK='TRUE';
      ALLOW_CONNECT='TRUE';
  end_pin;
  body
      PART_NAME='PICOPROBE_BXA';
      BODY_NAME='PICOPROBE_BXA';
      PHYS_DES_PREFIX='J';
      CLASS='IO';
      STANDARD='';
      LIFECYCLE='';
      JEDEC_TYPE='TRIANG_LAUNCH_3PXB';
      ALT_SYMBOLS='';
      DESCRIPTION='Probe for DELTA-L 4.0 measurement';
      MANUFTR='';
      MANUF_PN='';
      RD_CMPLS_LVL='';
      CMPLS_LVL='';
      DIP_SMD='';
      FROM_PJ='';
      DATA='TRIANG_LAUNCH_3PXB.pdf';
      FP_ECN='TRIANG_LAUNCH_3PXB.xlsx';
      EE_CHECK_LIST='';
      STATUS='';
      PSL='';
      PREFERENCE='';
      CREATOR='';
      CREATEDAY='20200107';
      ESD_CDM='';
      ESD_HBM='';
      ESD_MM='';
      MSD='';
      PIN_LENGTH_LONG_PIN='';
      PIN_LENGTH_SHORT_PIN='';
      PARENT_PART_TYPE='PICOPROBE_BXA';
      PARENT_PPT='PICOPROBE_BXA';
      PARENT_PPT_PART='PICOPROBE_BXA-DELTA-L 4.0,SMLF,EMPTY,TP33';
  end_body;
end_primitive;
primitive 'PRTR5V0U2X-PRTR5V0U2X,SMLF,IC,A';
  pin
    'IO1':
      PIN_NUMBER='(2)';
      BIDIRECTIONAL='TRUE';
      INPUT_LOAD='(-0.01,0.01)';
      OUTPUT_LOAD='(1.0,-1.0)';
      PINUSE='BI';
    'GND':
      PIN_NUMBER='(1)';
      PINUSE='POWER';
      NO_LOAD_CHECK='Both';
      NO_IO_CHECK='Both';
      NO_ASSERT_CHECK='TRUE';
      NO_DIR_CHECK='TRUE';
      ALLOW_CONNECT='TRUE';
    'VCC':
      PIN_NUMBER='(4)';
      PINUSE='POWER';
      NO_LOAD_CHECK='Both';
      NO_IO_CHECK='Both';
      NO_ASSERT_CHECK='TRUE';
      NO_DIR_CHECK='TRUE';
      ALLOW_CONNECT='TRUE';
    'IO2':
      PIN_NUMBER='(3)';
      BIDIRECTIONAL='TRUE';
      INPUT_LOAD='(-0.01,0.01)';
      OUTPUT_LOAD='(1.0,-1.0)';
      PINUSE='BI';
  end_pin;
  body
      PART_NAME='PRTR5V0U2X';
      BODY_NAME='PRTR5V0U2X';
      PHYS_DES_PREFIX='U';
      CLASS='IC';
      STANDARD='';
      LIFECYCLE='';
      JEDEC_TYPE='SOT143XB';
      DESCRIPTION='IC OTHER (4P) PRTR5V0U2X (SOT143B)';
      MANUFTR='NXP';
      MANUF_PN='PRTR5V0U2X';
      RD_CMPLS_LVL='EP(V1)';
      CMPLS_LVL='EP(V1)';
      FROM_PJ='S1M-MARK';
      DIP_SMD='';
      DATA='NXP_PRTR5V0U2X.pdf';
      EE_CHECK_LIST='';
      FP_ECN='';
      PSL='';
      CREATOR='';
      STATUS='';
      CREATEDAY='20140312';
      PARENT_PART_TYPE='PRTR5V0U2X';
      PARENT_PPT='PRTR5V0U2X';
      PARENT_PPT_PART='PRTR5V0U2X-PRTR5V0U2X,SMLF,IC,AL5V0U2X000';
  end_body;
end_primitive;
primitive 'Q_CAP_0402-0.1UF,25V,10%,EMPTYA';
  pin
    'A':
      PIN_NUMBER='(1)';
      PINUSE='UNSPEC';
      NO_LOAD_CHECK='BOTH';
      NO_IO_CHECK='BOTH';
      ALLOW_CONNECT='TRUE';
      PIN_GROUP='1';
    'B':
      PIN_NUMBER='(2)';
      PINUSE='UNSPEC';
      NO_LOAD_CHECK='BOTH';
      NO_IO_CHECK='BOTH';
      ALLOW_CONNECT='TRUE';
      PIN_GROUP='1';
  end_pin;
  body
      PART_NAME='Q_CAP';
      PHYS_DES_PREFIX='C';
      STANDARD='';
      LIFECYCLE='';
      ASS_PART='';
      JEDEC_TYPE='C0402';
      ALT_SYMBOLS='(C0402_OCTAGONXA,C0402-0201)';
      VALUE='NA';
      RATED_VOLTAGE='25V';
      TOL='10%';
      CLASS='IO';
      DESCRIPTION='CAP CHIP 0.1U 25V(+-10%,X7R,0402)';
      COMPONENT_TYPE='CHIP0402';
      LEAD_LENGTH='';
      LPID='';
      DATE='20160113';
      PARENT_PART_TYPE='Q_CAP';
      PARENT_PPT='Q_CAP';
      PARENT_PPT_PART='Q_CAP_0402-0.1UF,25V,10%,EMPTY,CH4104K1B00';
  end_body;
end_primitive;
primitive 'Q_CAP_0402-0.1UF,25V,10%,X7R,CA';
  pin
    'A':
      PIN_NUMBER='(1)';
      PINUSE='UNSPEC';
      NO_LOAD_CHECK='BOTH';
      NO_IO_CHECK='BOTH';
      ALLOW_CONNECT='TRUE';
      PIN_GROUP='1';
    'B':
      PIN_NUMBER='(2)';
      PINUSE='UNSPEC';
      NO_LOAD_CHECK='BOTH';
      NO_IO_CHECK='BOTH';
      ALLOW_CONNECT='TRUE';
      PIN_GROUP='1';
  end_pin;
  body
      PART_NAME='Q_CAP';
      PHYS_DES_PREFIX='C';
      STANDARD='';
      LIFECYCLE='';
      ASS_PART='';
      JEDEC_TYPE='C0402';
      ALT_SYMBOLS='(C0402_OCTAGONXA,C0402-0201)';
      VALUE='0.1UF';
      RATED_VOLTAGE='25V';
      TOL='10%';
      CLASS='DISCRETE';
      DESCRIPTION='CAP CHIP 0.1U 25V(+-10%,X7R,0402)';
      COMPONENT_TYPE='CHIP0402';
      LEAD_LENGTH='';
      LPID='';
      DATE='20160113';
      PARENT_PART_TYPE='Q_CAP';
      PARENT_PPT='Q_CAP';
      PARENT_PPT_PART='Q_CAP_0402-0.1UF,25V,10%,X7R,CH4104K1B00';
  end_body;
end_primitive;
primitive 'Q_CAP_0402-0.22UF,16V,10%,EMPTA';
  pin
    'A':
      PIN_NUMBER='(1)';
      PINUSE='UNSPEC';
      NO_LOAD_CHECK='BOTH';
      NO_IO_CHECK='BOTH';
      ALLOW_CONNECT='TRUE';
      PIN_GROUP='1';
    'B':
      PIN_NUMBER='(2)';
      PINUSE='UNSPEC';
      NO_LOAD_CHECK='BOTH';
      NO_IO_CHECK='BOTH';
      ALLOW_CONNECT='TRUE';
      PIN_GROUP='1';
  end_pin;
  body
      PART_NAME='Q_CAP';
      PHYS_DES_PREFIX='C';
      STANDARD='End of Design';
      LIFECYCLE='Comp-Approve';
      ASS_PART='';
      JEDEC_TYPE='C0402';
      ALT_SYMBOLS='(C0402_OCTAGONXA,C0402-0201)';
      VALUE='NA';
      RATED_VOLTAGE='16V';
      TOL='10%';
      CLASS='IO';
      DESCRIPTION='CAP CHIP 0.22U 16V(10%,X7R,0402)';
      COMPONENT_TYPE='CHIP0402';
      LEAD_LENGTH='';
      LPID='';
      DATE='20100916';
      PARENT_PART_TYPE='Q_CAP';
      PARENT_PPT='Q_CAP';
      PARENT_PPT_PART='Q_CAP_0402-0.22UF,16V,10%,EMPTY,CH4223K1B00';
  end_body;
end_primitive;
primitive 'Q_CAP_0402-0.22UF,16V,10%,X7R,A';
  pin
    'A':
      PIN_NUMBER='(1)';
      PINUSE='UNSPEC';
      NO_LOAD_CHECK='BOTH';
      NO_IO_CHECK='BOTH';
      ALLOW_CONNECT='TRUE';
      PIN_GROUP='1';
    'B':
      PIN_NUMBER='(2)';
      PINUSE='UNSPEC';
      NO_LOAD_CHECK='BOTH';
      NO_IO_CHECK='BOTH';
      ALLOW_CONNECT='TRUE';
      PIN_GROUP='1';
  end_pin;
  body
      PART_NAME='Q_CAP';
      PHYS_DES_PREFIX='C';
      STANDARD='End of Design';
      LIFECYCLE='Comp-Approve';
      ASS_PART='';
      JEDEC_TYPE='C0402';
      ALT_SYMBOLS='(C0402_OCTAGONXA,C0402-0201)';
      VALUE='0.22UF';
      RATED_VOLTAGE='16V';
      TOL='10%';
      CLASS='DISCRETE';
      DESCRIPTION='CAP CHIP 0.22U 16V(10%,X7R,0402)';
      COMPONENT_TYPE='CHIP0402';
      LEAD_LENGTH='';
      LPID='';
      DATE='20100916';
      PARENT_PART_TYPE='Q_CAP';
      PARENT_PPT='Q_CAP';
      PARENT_PPT_PART='Q_CAP_0402-0.22UF,16V,10%,X7R,CH4223K1B00';
  end_body;
end_primitive;
primitive 'Q_CAP_0402-100PF,50V,5%,EMPTY,A';
  pin
    'A':
      PIN_NUMBER='(1)';
      PINUSE='UNSPEC';
      NO_LOAD_CHECK='BOTH';
      NO_IO_CHECK='BOTH';
      ALLOW_CONNECT='TRUE';
      PIN_GROUP='1';
    'B':
      PIN_NUMBER='(2)';
      PINUSE='UNSPEC';
      NO_LOAD_CHECK='BOTH';
      NO_IO_CHECK='BOTH';
      ALLOW_CONNECT='TRUE';
      PIN_GROUP='1';
  end_pin;
  body
      PART_NAME='Q_CAP';
      PHYS_DES_PREFIX='C';
      STANDARD='End of Design';
      LIFECYCLE='Comp-Approve';
      ASS_PART='';
      JEDEC_TYPE='C0402';
      ALT_SYMBOLS='(C0402-0201)';
      VALUE='NA';
      RATED_VOLTAGE='50V';
      TOL='5%';
      CLASS='IO';
      DESCRIPTION='CAP CHIP 100P 50V(+-5%.X7R.0402)';
      COMPONENT_TYPE='CHIP0402';
      LEAD_LENGTH='';
      LPID='';
      DATE='20100929';
      PARENT_PART_TYPE='Q_CAP';
      PARENT_PPT='Q_CAP';
      PARENT_PPT_PART='Q_CAP_0402-100PF,50V,5%,EMPTY,CH11006JB18';
  end_body;
end_primitive;
primitive 'Q_CAP_0402-100PF,50V,5%,NPO,CHA';
  pin
    'A':
      PIN_NUMBER='(1)';
      PINUSE='UNSPEC';
      NO_LOAD_CHECK='BOTH';
      NO_IO_CHECK='BOTH';
      ALLOW_CONNECT='TRUE';
      PIN_GROUP='1';
    'B':
      PIN_NUMBER='(2)';
      PINUSE='UNSPEC';
      NO_LOAD_CHECK='BOTH';
      NO_IO_CHECK='BOTH';
      ALLOW_CONNECT='TRUE';
      PIN_GROUP='1';
  end_pin;
  body
      PART_NAME='Q_CAP';
      PHYS_DES_PREFIX='C';
      STANDARD='';
      LIFECYCLE='';
      ASS_PART='';
      JEDEC_TYPE='C0402';
      ALT_SYMBOLS='(C0402-0201)';
      VALUE='100PF';
      RATED_VOLTAGE='50V';
      TOL='5%';
      CLASS='DISCRETE';
      DESCRIPTION='CAP CHIP 100P 50V(+-5%,NPO,0402)';
      COMPONENT_TYPE='CHIP0402';
      LEAD_LENGTH='';
      LPID='';
      DATE='20100618';
      PARENT_PART_TYPE='Q_CAP';
      PARENT_PPT='Q_CAP';
      PARENT_PPT_PART='Q_CAP_0402-100PF,50V,5%,NPO,CH11006JB00';
  end_body;
end_primitive;
primitive 'Q_CAP_0402-10PF,50V,1%,NPO,TMPA';
  pin
    'A':
      PIN_NUMBER='(1)';
      PINUSE='UNSPEC';
      NO_LOAD_CHECK='BOTH';
      NO_IO_CHECK='BOTH';
      ALLOW_CONNECT='TRUE';
      PIN_GROUP='1';
    'B':
      PIN_NUMBER='(2)';
      PINUSE='UNSPEC';
      NO_LOAD_CHECK='BOTH';
      NO_IO_CHECK='BOTH';
      ALLOW_CONNECT='TRUE';
      PIN_GROUP='1';
  end_pin;
  body
      PART_NAME='Q_CAP';
      PHYS_DES_PREFIX='C';
      STANDARD='';
      LIFECYCLE='';
      ASS_PART='';
      JEDEC_TYPE='C0402';
      ALT_SYMBOLS='(C0402-0201)';
      VALUE='10PF';
      RATED_VOLTAGE='50V';
      TOL='1%';
      CLASS='DISCRETE';
      DESCRIPTION='CHIP0402';
      COMPONENT_TYPE='CHIP0402';
      LEAD_LENGTH='';
      LPID='';
      DATE='';
      PARENT_PART_TYPE='Q_CAP';
      PARENT_PPT='Q_CAP';
      PARENT_PPT_PART='Q_CAP_0402-10PF,50V,1%,NPO,TMP_QCH0106F0B00';
  end_body;
end_primitive;
primitive 'Q_CAP_0402-15PF,50V,5%,C0G,CH0A';
  pin
    'A':
      PIN_NUMBER='(1)';
      PINUSE='UNSPEC';
      NO_LOAD_CHECK='BOTH';
      NO_IO_CHECK='BOTH';
      ALLOW_CONNECT='TRUE';
      PIN_GROUP='1';
    'B':
      PIN_NUMBER='(2)';
      PINUSE='UNSPEC';
      NO_LOAD_CHECK='BOTH';
      NO_IO_CHECK='BOTH';
      ALLOW_CONNECT='TRUE';
      PIN_GROUP='1';
  end_pin;
  body
      PART_NAME='Q_CAP';
      PHYS_DES_PREFIX='C';
      STANDARD='';
      LIFECYCLE='';
      ASS_PART='';
      JEDEC_TYPE='C0402';
      ALT_SYMBOLS='(C0402-0201)';
      VALUE='15PF';
      RATED_VOLTAGE='50V';
      TOL='5%';
      CLASS='DISCRETE';
      DESCRIPTION='CAP CHIP 15P 50V(+-5% C0G 0402)';
      COMPONENT_TYPE='CHIP0402';
      LEAD_LENGTH='';
      LPID='';
      DATE='20110207';
      PARENT_PART_TYPE='Q_CAP';
      PARENT_PPT='Q_CAP';
      PARENT_PPT_PART='Q_CAP_0402-15PF,50V,5%,C0G,CH01506JB06';
  end_body;
end_primitive;
primitive 'Q_CAP_0402-18PF,50V,5%,C0G,CH0A';
  pin
    'A':
      PIN_NUMBER='(1)';
      PINUSE='UNSPEC';
      NO_LOAD_CHECK='BOTH';
      NO_IO_CHECK='BOTH';
      ALLOW_CONNECT='TRUE';
      PIN_GROUP='1';
    'B':
      PIN_NUMBER='(2)';
      PINUSE='UNSPEC';
      NO_LOAD_CHECK='BOTH';
      NO_IO_CHECK='BOTH';
      ALLOW_CONNECT='TRUE';
      PIN_GROUP='1';
  end_pin;
  body
      PART_NAME='Q_CAP';
      PHYS_DES_PREFIX='C';
      STANDARD='';
      LIFECYCLE='';
      ASS_PART='';
      JEDEC_TYPE='C0402';
      ALT_SYMBOLS='(C0402-0201)';
      VALUE='18PF';
      RATED_VOLTAGE='50V';
      TOL='5%';
      CLASS='DISCRETE';
      DESCRIPTION='CAP CHIP 18P 50V(+-5% C0G 0402)';
      COMPONENT_TYPE='CHIP0402';
      LEAD_LENGTH='';
      LPID='';
      DATE='20110119';
      PARENT_PART_TYPE='Q_CAP';
      PARENT_PPT='Q_CAP';
      PARENT_PPT_PART='Q_CAP_0402-18PF,50V,5%,C0G,CH01806JB07';
  end_body;
end_primitive;
primitive 'Q_CAP_0402-1UF,16V,10%,EMPTY,TA';
  pin
    'A':
      PIN_NUMBER='(1)';
      PINUSE='UNSPEC';
      NO_LOAD_CHECK='BOTH';
      NO_IO_CHECK='BOTH';
      ALLOW_CONNECT='TRUE';
      PIN_GROUP='1';
    'B':
      PIN_NUMBER='(2)';
      PINUSE='UNSPEC';
      NO_LOAD_CHECK='BOTH';
      NO_IO_CHECK='BOTH';
      ALLOW_CONNECT='TRUE';
      PIN_GROUP='1';
  end_pin;
  body
      PART_NAME='Q_CAP';
      PHYS_DES_PREFIX='C';
      STANDARD='End of Design';
      LIFECYCLE='Comp-Approve';
      ASS_PART='';
      JEDEC_TYPE='C0402';
      ALT_SYMBOLS='(C0402-0201)';
      VALUE='NA';
      RATED_VOLTAGE='16V';
      TOL='10%';
      CLASS='IO';
      DESCRIPTION='CHIP0402';
      COMPONENT_TYPE='CHIP0402';
      LEAD_LENGTH='';
      LPID='';
      DATE='';
      PARENT_PART_TYPE='Q_CAP';
      PARENT_PPT='Q_CAP';
      PARENT_PPT_PART='Q_CAP_0402-1UF,16V,10%,EMPTY,TMP_QCH5103K9B00';
  end_body;
end_primitive;
primitive 'Q_CAP_0402-2200PF,50V,10%,X7R,A';
  pin
    'A':
      PIN_NUMBER='(1)';
      PINUSE='UNSPEC';
      NO_LOAD_CHECK='BOTH';
      NO_IO_CHECK='BOTH';
      ALLOW_CONNECT='TRUE';
      PIN_GROUP='1';
    'B':
      PIN_NUMBER='(2)';
      PINUSE='UNSPEC';
      NO_LOAD_CHECK='BOTH';
      NO_IO_CHECK='BOTH';
      ALLOW_CONNECT='TRUE';
      PIN_GROUP='1';
  end_pin;
  body
      PART_NAME='Q_CAP';
      PHYS_DES_PREFIX='C';
      STANDARD='';
      LIFECYCLE='';
      ASS_PART='';
      JEDEC_TYPE='C0402';
      ALT_SYMBOLS='(C0402-0201)';
      VALUE='2200PF';
      RATED_VOLTAGE='50V';
      TOL='10%';
      CLASS='DISCRETE';
      DESCRIPTION='CAP CHIP 2200P 50V(+-10%,X7R,0402)';
      COMPONENT_TYPE='CHIP0402';
      LEAD_LENGTH='';
      LPID='';
      DATE='';
      PARENT_PART_TYPE='Q_CAP';
      PARENT_PPT='Q_CAP';
      PARENT_PPT_PART='Q_CAP_0402-2200PF,50V,10%,X7R,TMP_QCH22206KB16';
  end_body;
end_primitive;
primitive 'Q_CAP_0402-22PF,50V,5%,NPO,TMPA';
  pin
    'A':
      PIN_NUMBER='(1)';
      PINUSE='UNSPEC';
      NO_LOAD_CHECK='BOTH';
      NO_IO_CHECK='BOTH';
      ALLOW_CONNECT='TRUE';
      PIN_GROUP='1';
    'B':
      PIN_NUMBER='(2)';
      PINUSE='UNSPEC';
      NO_LOAD_CHECK='BOTH';
      NO_IO_CHECK='BOTH';
      ALLOW_CONNECT='TRUE';
      PIN_GROUP='1';
  end_pin;
  body
      PART_NAME='Q_CAP';
      PHYS_DES_PREFIX='C';
      STANDARD='';
      LIFECYCLE='';
      ASS_PART='';
      JEDEC_TYPE='C0402';
      ALT_SYMBOLS='(C0402-0201)';
      VALUE='22PF';
      RATED_VOLTAGE='50V';
      TOL='5%';
      CLASS='DISCRETE';
      DESCRIPTION='CHIP0402';
      COMPONENT_TYPE='CHIP0402';
      LEAD_LENGTH='';
      LPID='';
      DATE='';
      PARENT_PART_TYPE='Q_CAP';
      PARENT_PPT='Q_CAP';
      PARENT_PPT_PART='Q_CAP_0402-22PF,50V,5%,NPO,TMP_QCH02206JB08';
  end_body;
end_primitive;
primitive 'Q_CAP_0402-3300PF,50V,10%,X7R,A';
  pin
    'A':
      PIN_NUMBER='(1)';
      PINUSE='UNSPEC';
      NO_LOAD_CHECK='BOTH';
      NO_IO_CHECK='BOTH';
      ALLOW_CONNECT='TRUE';
      PIN_GROUP='1';
    'B':
      PIN_NUMBER='(2)';
      PINUSE='UNSPEC';
      NO_LOAD_CHECK='BOTH';
      NO_IO_CHECK='BOTH';
      ALLOW_CONNECT='TRUE';
      PIN_GROUP='1';
  end_pin;
  body
      PART_NAME='Q_CAP';
      PHYS_DES_PREFIX='C';
      STANDARD='';
      LIFECYCLE='';
      ASS_PART='';
      JEDEC_TYPE='C0402';
      ALT_SYMBOLS='(C0402-0201)';
      VALUE='3300PF';
      RATED_VOLTAGE='50V';
      TOL='10%';
      CLASS='DISCRETE';
      DESCRIPTION='CHIP0402';
      COMPONENT_TYPE='CHIP0402';
      LEAD_LENGTH='';
      LPID='';
      DATE='';
      PARENT_PART_TYPE='Q_CAP';
      PARENT_PPT='Q_CAP';
      PARENT_PPT_PART='Q_CAP_0402-3300PF,50V,10%,X7R,TMP_QCH2336K1B12';
  end_body;
end_primitive;
primitive 'Q_CAP_0402-470PF,50V,10%,X7R,TA';
  pin
    'A':
      PIN_NUMBER='(1)';
      PINUSE='UNSPEC';
      NO_LOAD_CHECK='BOTH';
      NO_IO_CHECK='BOTH';
      ALLOW_CONNECT='TRUE';
      PIN_GROUP='1';
    'B':
      PIN_NUMBER='(2)';
      PINUSE='UNSPEC';
      NO_LOAD_CHECK='BOTH';
      NO_IO_CHECK='BOTH';
      ALLOW_CONNECT='TRUE';
      PIN_GROUP='1';
  end_pin;
  body
      PART_NAME='Q_CAP';
      PHYS_DES_PREFIX='C';
      STANDARD='';
      LIFECYCLE='';
      ASS_PART='';
      JEDEC_TYPE='C0402';
      ALT_SYMBOLS='(C0402-0201)';
      VALUE='470PF';
      RATED_VOLTAGE='50V';
      TOL='10%';
      CLASS='DISCRETE';
      DESCRIPTION='CHIP0402';
      COMPONENT_TYPE='CHIP0402';
      LEAD_LENGTH='';
      LPID='';
      DATE='';
      PARENT_PART_TYPE='Q_CAP';
      PARENT_PPT='Q_CAP';
      PARENT_PPT_PART='Q_CAP_0402-470PF,50V,10%,X7R,TMP_QCH14706KB18';
  end_body;
end_primitive;
primitive 'Q_CAP_0603-1UF,16V,10%,EMPTY,TA';
  pin
    'A':
      PIN_NUMBER='(1)';
      PINUSE='UNSPEC';
      NO_LOAD_CHECK='BOTH';
      NO_IO_CHECK='BOTH';
      ALLOW_CONNECT='TRUE';
      PIN_GROUP='1';
    'B':
      PIN_NUMBER='(2)';
      PINUSE='UNSPEC';
      NO_LOAD_CHECK='BOTH';
      NO_IO_CHECK='BOTH';
      ALLOW_CONNECT='TRUE';
      PIN_GROUP='1';
  end_pin;
  body
      PART_NAME='Q_CAP';
      PHYS_DES_PREFIX='C';
      STANDARD='End of Design';
      LIFECYCLE='Comp-Approve';
      ASS_PART='';
      JEDEC_TYPE='C0603';
      ALT_SYMBOLS='(SMC0603AW)';
      VALUE='NA';
      RATED_VOLTAGE='16V';
      TOL='10%';
      CLASS='IO';
      DESCRIPTION='CHIP0603';
      COMPONENT_TYPE='CHIP0603';
      LEAD_LENGTH='';
      LPID='';
      DATE='';
      PARENT_PART_TYPE='Q_CAP';
      PARENT_PPT='Q_CAP';
      PARENT_PPT_PART='Q_CAP_0603-1UF,16V,10%,EMPTY,TMP_QCH5103K1900';
  end_body;
end_primitive;
primitive 'Q_CAP_0805-22UF,4V,20%,X6S,TMPA';
  pin
    'A':
      PIN_NUMBER='(1)';
      PINUSE='UNSPEC';
      NO_LOAD_CHECK='BOTH';
      NO_IO_CHECK='BOTH';
      ALLOW_CONNECT='TRUE';
      PIN_GROUP='1';
    'B':
      PIN_NUMBER='(2)';
      PINUSE='UNSPEC';
      NO_LOAD_CHECK='BOTH';
      NO_IO_CHECK='BOTH';
      ALLOW_CONNECT='TRUE';
      PIN_GROUP='1';
  end_pin;
  body
      PART_NAME='Q_CAP';
      PHYS_DES_PREFIX='C';
      STANDARD='End of Design';
      LIFECYCLE='Comp-Approve';
      ASS_PART='';
      JEDEC_TYPE='C0805_H61';
      ALT_SYMBOLS='(SMC0805AW)';
      VALUE='22UF';
      RATED_VOLTAGE='4V';
      TOL='20%';
      CLASS='DISCRETE';
      DESCRIPTION='CHIP0805';
      COMPONENT_TYPE='CHIP0805';
      LEAD_LENGTH='';
      LPID='';
      DATE='';
      PARENT_PART_TYPE='Q_CAP';
      PARENT_PPT='Q_CAP';
      PARENT_PPT_PART='Q_CAP_0805-22UF,4V,20%,X6S,TMP_QCH622KMEA01';
  end_body;
end_primitive;
primitive 'Q_CAP_C0402-0.001UF,50V,10%,EMA';
  pin
    'A':
      PIN_NUMBER='(1)';
      PINUSE='UNSPEC';
      NO_LOAD_CHECK='BOTH';
      NO_IO_CHECK='BOTH';
      ALLOW_CONNECT='TRUE';
      PIN_GROUP='1';
    'B':
      PIN_NUMBER='(2)';
      PINUSE='UNSPEC';
      NO_LOAD_CHECK='BOTH';
      NO_IO_CHECK='BOTH';
      ALLOW_CONNECT='TRUE';
      PIN_GROUP='1';
  end_pin;
  body
      PART_NAME='Q_CAP';
      PHYS_DES_PREFIX='C';
      STANDARD='End of Design';
      LIFECYCLE='Comp-Release Qty';
      ASS_PART='';
      JEDEC_TYPE='C0402';
      ALT_SYMBOLS='(C0402-0201)';
      VALUE='NA';
      RATED_VOLTAGE='50V';
      TOL='10%';
      CLASS='IO';
      DESCRIPTION='CAP CHIP 0.001U 50V(10%,X7R,0402)';
      COMPONENT_TYPE='CHIP0402';
      LEAD_LENGTH='';
      LPID='';
      DATE='20200218';
      PARENT_PART_TYPE='Q_CAP';
      PARENT_PPT='Q_CAP';
      PARENT_PPT_PART='Q_CAP_C0402-0.001UF,50V,10%,EMPTY,CH30106KB19';
  end_body;
end_primitive;
primitive 'Q_CAP_C0402-0.01UF,50V,10%,EMPA';
  pin
    'A':
      PIN_NUMBER='(1)';
      PINUSE='UNSPEC';
      NO_LOAD_CHECK='BOTH';
      NO_IO_CHECK='BOTH';
      ALLOW_CONNECT='TRUE';
      PIN_GROUP='1';
    'B':
      PIN_NUMBER='(2)';
      PINUSE='UNSPEC';
      NO_LOAD_CHECK='BOTH';
      NO_IO_CHECK='BOTH';
      ALLOW_CONNECT='TRUE';
      PIN_GROUP='1';
  end_pin;
  body
      PART_NAME='Q_CAP';
      PHYS_DES_PREFIX='C';
      STANDARD='';
      LIFECYCLE='';
      ASS_PART='';
      JEDEC_TYPE='C0402';
      ALT_SYMBOLS='(C0402_OCTAGONXA,C0402-0201)';
      VALUE='NA';
      RATED_VOLTAGE='50V';
      TOL='10%';
      CLASS='IO';
      DESCRIPTION='CAP CHIP 0.01U 50V(+-10%,X7R,0402)';
      COMPONENT_TYPE='CHIP0402';
      LEAD_LENGTH='';
      LPID='';
      DATE='20120326';
      PARENT_PART_TYPE='Q_CAP';
      PARENT_PPT='Q_CAP';
      PARENT_PPT_PART='Q_CAP_C0402-0.01UF,50V,10%,EMPTY,CH31006KB18';
  end_body;
end_primitive;
primitive 'Q_CAP_C0402-0.01UF,50V,10%,X7RA';
  pin
    'A':
      PIN_NUMBER='(1)';
      PINUSE='UNSPEC';
      NO_LOAD_CHECK='BOTH';
      NO_IO_CHECK='BOTH';
      ALLOW_CONNECT='TRUE';
      PIN_GROUP='1';
    'B':
      PIN_NUMBER='(2)';
      PINUSE='UNSPEC';
      NO_LOAD_CHECK='BOTH';
      NO_IO_CHECK='BOTH';
      ALLOW_CONNECT='TRUE';
      PIN_GROUP='1';
  end_pin;
  body
      PART_NAME='Q_CAP';
      PHYS_DES_PREFIX='C';
      STANDARD='';
      LIFECYCLE='';
      ASS_PART='';
      JEDEC_TYPE='C0402';
      ALT_SYMBOLS='(C0402_OCTAGONXA,C0402-0201)';
      VALUE='0.01UF';
      RATED_VOLTAGE='50V';
      TOL='10%';
      CLASS='DISCRETE';
      DESCRIPTION='CAP CHIP 0.01U 50V(+-10%,X7R,0402)';
      COMPONENT_TYPE='CHIP0402';
      LEAD_LENGTH='';
      LPID='';
      DATE='20120326';
      PARENT_PART_TYPE='Q_CAP';
      PARENT_PPT='Q_CAP';
      PARENT_PPT_PART='Q_CAP_C0402-0.01UF,50V,10%,X7R,CH31006KB18';
  end_body;
end_primitive;
primitive 'Q_CAP_C0402-10UF,6.3V,20%,X6S,A';
  pin
    'A':
      PIN_NUMBER='(1)';
      PINUSE='UNSPEC';
      NO_LOAD_CHECK='BOTH';
      NO_IO_CHECK='BOTH';
      ALLOW_CONNECT='TRUE';
      PIN_GROUP='1';
    'B':
      PIN_NUMBER='(2)';
      PINUSE='UNSPEC';
      NO_LOAD_CHECK='BOTH';
      NO_IO_CHECK='BOTH';
      ALLOW_CONNECT='TRUE';
      PIN_GROUP='1';
  end_pin;
  body
      PART_NAME='Q_CAP';
      PHYS_DES_PREFIX='C';
      STANDARD='';
      LIFECYCLE='';
      ASS_PART='';
      JEDEC_TYPE='C0402';
      ALT_SYMBOLS='(C0402_OCTAGONXA,C0402-0201)';
      VALUE='10UF';
      RATED_VOLTAGE='6.3V';
      TOL='20%';
      CLASS='DISCRETE';
      DESCRIPTION='CAP CHIP 10UF 6.3V(+-20%,X6S,0402)';
      COMPONENT_TYPE='CHIP0402';
      LEAD_LENGTH='';
      LPID='';
      DATE='20170330';
      PARENT_PART_TYPE='Q_CAP';
      PARENT_PPT='Q_CAP';
      PARENT_PPT_PART='Q_CAP_C0402-10UF,6.3V,20%,X6S,CH6101MEB01';
  end_body;
end_primitive;
primitive 'Q_CAP_C0402-1UF,25V,10%,EMPTY,A';
  pin
    'A':
      PIN_NUMBER='(1)';
      PINUSE='UNSPEC';
      NO_LOAD_CHECK='BOTH';
      NO_IO_CHECK='BOTH';
      ALLOW_CONNECT='TRUE';
      PIN_GROUP='1';
    'B':
      PIN_NUMBER='(2)';
      PINUSE='UNSPEC';
      NO_LOAD_CHECK='BOTH';
      NO_IO_CHECK='BOTH';
      ALLOW_CONNECT='TRUE';
      PIN_GROUP='1';
  end_pin;
  body
      PART_NAME='Q_CAP';
      PHYS_DES_PREFIX='C';
      STANDARD='';
      LIFECYCLE='';
      ASS_PART='';
      JEDEC_TYPE='C0402';
      ALT_SYMBOLS='(C0402_OCTAGONXA,C0402-0201)';
      VALUE='NA';
      RATED_VOLTAGE='25V';
      TOL='10%';
      CLASS='IO';
      DESCRIPTION='CAP CHIP 1UF 25V(+-10%,X6S,0402)';
      COMPONENT_TYPE='CHIP0402';
      LEAD_LENGTH='';
      LPID='';
      DATE='20140327';
      PARENT_PART_TYPE='Q_CAP';
      PARENT_PPT='Q_CAP';
      PARENT_PPT_PART='Q_CAP_C0402-1UF,25V,10%,EMPTY,CH5104KEB02';
  end_body;
end_primitive;
primitive 'Q_CAP_C0402-1UF,25V,10%,X6S,CHA';
  pin
    'A':
      PIN_NUMBER='(1)';
      PINUSE='UNSPEC';
      NO_LOAD_CHECK='BOTH';
      NO_IO_CHECK='BOTH';
      ALLOW_CONNECT='TRUE';
      PIN_GROUP='1';
    'B':
      PIN_NUMBER='(2)';
      PINUSE='UNSPEC';
      NO_LOAD_CHECK='BOTH';
      NO_IO_CHECK='BOTH';
      ALLOW_CONNECT='TRUE';
      PIN_GROUP='1';
  end_pin;
  body
      PART_NAME='Q_CAP';
      PHYS_DES_PREFIX='C';
      STANDARD='';
      LIFECYCLE='';
      ASS_PART='';
      JEDEC_TYPE='C0402';
      ALT_SYMBOLS='(C0402_OCTAGONXA,C0402-0201)';
      VALUE='1UF';
      RATED_VOLTAGE='25V';
      TOL='10%';
      CLASS='DISCRETE';
      DESCRIPTION='CAP CHIP 1UF 25V(+-10%,X6S,0402)';
      COMPONENT_TYPE='CHIP0402';
      LEAD_LENGTH='';
      LPID='';
      DATE='20140327';
      PARENT_PART_TYPE='Q_CAP';
      PARENT_PPT='Q_CAP';
      PARENT_PPT_PART='Q_CAP_C0402-1UF,25V,10%,X6S,CH5104KEB02';
  end_body;
end_primitive;
primitive 'Q_CAP_C0402-2.2UF,10V,10%,X6S,A';
  pin
    'A':
      PIN_NUMBER='(1)';
      PINUSE='UNSPEC';
      NO_LOAD_CHECK='BOTH';
      NO_IO_CHECK='BOTH';
      ALLOW_CONNECT='TRUE';
      PIN_GROUP='1';
    'B':
      PIN_NUMBER='(2)';
      PINUSE='UNSPEC';
      NO_LOAD_CHECK='BOTH';
      NO_IO_CHECK='BOTH';
      ALLOW_CONNECT='TRUE';
      PIN_GROUP='1';
  end_pin;
  body
      PART_NAME='Q_CAP';
      PHYS_DES_PREFIX='C';
      STANDARD='';
      LIFECYCLE='';
      ASS_PART='';
      JEDEC_TYPE='C0402';
      ALT_SYMBOLS='(C0402_OCTAGONXA,C0402-0201)';
      VALUE='2.2UF';
      RATED_VOLTAGE='10V';
      TOL='10%';
      CLASS='DISCRETE';
      DESCRIPTION='CAP CHIP 2.2UF 10V(+-10%,X6S,0402)';
      COMPONENT_TYPE='CHIP0402';
      LEAD_LENGTH='';
      LPID='';
      DATE='20150612';
      PARENT_PART_TYPE='Q_CAP';
      PARENT_PPT='Q_CAP';
      PARENT_PPT_PART='Q_CAP_C0402-2.2UF,10V,10%,X6S,CH5222KEB01';
  end_body;
end_primitive;
primitive 'Q_CAP_C0402-4700P,25V,10%,EMPTA';
  pin
    'A':
      PIN_NUMBER='(1)';
      PINUSE='UNSPEC';
      NO_LOAD_CHECK='BOTH';
      NO_IO_CHECK='BOTH';
      ALLOW_CONNECT='TRUE';
      PIN_GROUP='1';
    'B':
      PIN_NUMBER='(2)';
      PINUSE='UNSPEC';
      NO_LOAD_CHECK='BOTH';
      NO_IO_CHECK='BOTH';
      ALLOW_CONNECT='TRUE';
      PIN_GROUP='1';
  end_pin;
  body
      PART_NAME='Q_CAP';
      PHYS_DES_PREFIX='C';
      STANDARD='';
      LIFECYCLE='';
      ASS_PART='';
      JEDEC_TYPE='C0402';
      ALT_SYMBOLS='(C0402-0201)';
      VALUE='NA';
      RATED_VOLTAGE='25V';
      TOL='10%';
      CLASS='IO';
      DESCRIPTION='CAP CHIP 4700P 25V(+-10%,X7R,0402)MUR';
      COMPONENT_TYPE='CHIP0402';
      LEAD_LENGTH='';
      LPID='';
      DATE='20150614';
      PARENT_PART_TYPE='Q_CAP';
      PARENT_PPT='Q_CAP';
      PARENT_PPT_PART='Q_CAP_C0402-4700P,25V,10%,EMPTY,CH2474K1B08';
  end_body;
end_primitive;
primitive 'Q_CAP_C0402-68PF,50V,5%,COG,CHA';
  pin
    'A':
      PIN_NUMBER='(1)';
      PINUSE='UNSPEC';
      NO_LOAD_CHECK='BOTH';
      NO_IO_CHECK='BOTH';
      ALLOW_CONNECT='TRUE';
      PIN_GROUP='1';
    'B':
      PIN_NUMBER='(2)';
      PINUSE='UNSPEC';
      NO_LOAD_CHECK='BOTH';
      NO_IO_CHECK='BOTH';
      ALLOW_CONNECT='TRUE';
      PIN_GROUP='1';
  end_pin;
  body
      PART_NAME='Q_CAP';
      PHYS_DES_PREFIX='C';
      STANDARD='';
      LIFECYCLE='';
      ASS_PART='';
      JEDEC_TYPE='C0402';
      ALT_SYMBOLS='(C0402-0201)';
      VALUE='68PF';
      RATED_VOLTAGE='50V';
      TOL='5%';
      CLASS='DISCRETE';
      DESCRIPTION='CAP CHIP 68P 50V(+-5%.COG.0402)';
      COMPONENT_TYPE='CHIP0402';
      LEAD_LENGTH='';
      LPID='';
      DATE='20170725';
      PARENT_PART_TYPE='Q_CAP';
      PARENT_PPT='Q_CAP';
      PARENT_PPT_PART='Q_CAP_C0402-68PF,50V,5%,COG,CH06806JB01';
  end_body;
end_primitive;
primitive 'Q_CAP_C0603-10UF,16V,20%,X6S,CA';
  pin
    'A':
      PIN_NUMBER='(1)';
      PINUSE='UNSPEC';
      NO_LOAD_CHECK='BOTH';
      NO_IO_CHECK='BOTH';
      ALLOW_CONNECT='TRUE';
      PIN_GROUP='1';
    'B':
      PIN_NUMBER='(2)';
      PINUSE='UNSPEC';
      NO_LOAD_CHECK='BOTH';
      NO_IO_CHECK='BOTH';
      ALLOW_CONNECT='TRUE';
      PIN_GROUP='1';
  end_pin;
  body
      PART_NAME='Q_CAP';
      PHYS_DES_PREFIX='C';
      STANDARD='';
      LIFECYCLE='';
      ASS_PART='';
      JEDEC_TYPE='C0603';
      ALT_SYMBOLS='(SMC0603AW)';
      VALUE='10UF';
      RATED_VOLTAGE='16V';
      TOL='20%';
      CLASS='DISCRETE';
      DESCRIPTION='CAP CHIP 10U 16V(+-20%,X6S,0603)';
      COMPONENT_TYPE='CHIP0603';
      LEAD_LENGTH='';
      LPID='';
      DATE='20140116';
      PARENT_PART_TYPE='Q_CAP';
      PARENT_PPT='Q_CAP';
      PARENT_PPT_PART='Q_CAP_C0603-10UF,16V,20%,X6S,CH6103ME902';
  end_body;
end_primitive;
primitive 'Q_CAP_C0603-22UF,10V,20%,EMPTYA';
  pin
    'A':
      PIN_NUMBER='(1)';
      PINUSE='UNSPEC';
      NO_LOAD_CHECK='BOTH';
      NO_IO_CHECK='BOTH';
      ALLOW_CONNECT='TRUE';
      PIN_GROUP='1';
    'B':
      PIN_NUMBER='(2)';
      PINUSE='UNSPEC';
      NO_LOAD_CHECK='BOTH';
      NO_IO_CHECK='BOTH';
      ALLOW_CONNECT='TRUE';
      PIN_GROUP='1';
  end_pin;
  body
      PART_NAME='Q_CAP';
      PHYS_DES_PREFIX='C';
      STANDARD='';
      LIFECYCLE='';
      ASS_PART='';
      JEDEC_TYPE='C0603';
      ALT_SYMBOLS='(SMC0603AW)';
      VALUE='NA';
      RATED_VOLTAGE='10V';
      TOL='20%';
      CLASS='IO';
      DESCRIPTION='CAP CHIP 22UF 10V(+-20%,X5R,0603)';
      COMPONENT_TYPE='CHIP0603';
      LEAD_LENGTH='';
      LPID='';
      DATE='20170801';
      PARENT_PART_TYPE='Q_CAP';
      PARENT_PPT='Q_CAP';
      PARENT_PPT_PART='Q_CAP_C0603-22UF,10V,20%,EMPTY,CH6222M9901';
  end_body;
end_primitive;
primitive 'Q_CAP_C0603-22UF,6.3V,20%,X6S,A';
  pin
    'A':
      PIN_NUMBER='(1)';
      PINUSE='UNSPEC';
      NO_LOAD_CHECK='BOTH';
      NO_IO_CHECK='BOTH';
      ALLOW_CONNECT='TRUE';
      PIN_GROUP='1';
    'B':
      PIN_NUMBER='(2)';
      PINUSE='UNSPEC';
      NO_LOAD_CHECK='BOTH';
      NO_IO_CHECK='BOTH';
      ALLOW_CONNECT='TRUE';
      PIN_GROUP='1';
  end_pin;
  body
      PART_NAME='Q_CAP';
      PHYS_DES_PREFIX='C';
      STANDARD='';
      LIFECYCLE='';
      ASS_PART='';
      JEDEC_TYPE='C0603';
      ALT_SYMBOLS='(SMC0603AW)';
      VALUE='22UF';
      RATED_VOLTAGE='6.3V';
      TOL='20%';
      CLASS='DISCRETE';
      DESCRIPTION='CAP CHIP 22U 6.3V(+-20%,X6S,0603)';
      COMPONENT_TYPE='CHIP0603';
      LEAD_LENGTH='';
      LPID='';
      DATE='20140327';
      PARENT_PART_TYPE='Q_CAP';
      PARENT_PPT='Q_CAP';
      PARENT_PPT_PART='Q_CAP_C0603-22UF,6.3V,20%,X6S,CH6221ME900';
  end_body;
end_primitive;
primitive 'Q_CAP_C0603-4.7UF,25V,10%,X6S,A';
  pin
    'A':
      PIN_NUMBER='(1)';
      PINUSE='UNSPEC';
      NO_LOAD_CHECK='BOTH';
      NO_IO_CHECK='BOTH';
      ALLOW_CONNECT='TRUE';
      PIN_GROUP='1';
    'B':
      PIN_NUMBER='(2)';
      PINUSE='UNSPEC';
      NO_LOAD_CHECK='BOTH';
      NO_IO_CHECK='BOTH';
      ALLOW_CONNECT='TRUE';
      PIN_GROUP='1';
  end_pin;
  body
      PART_NAME='Q_CAP';
      PHYS_DES_PREFIX='C';
      STANDARD='';
      LIFECYCLE='';
      ASS_PART='';
      JEDEC_TYPE='C0603';
      ALT_SYMBOLS='(SMC0603AW)';
      VALUE='4.7UF';
      RATED_VOLTAGE='25V';
      TOL='10%';
      CLASS='DISCRETE';
      DESCRIPTION='CAP CHIP 4.7UF 25V(+-10%,X6S,0603)';
      COMPONENT_TYPE='CHIP0603';
      LEAD_LENGTH='';
      LPID='';
      DATE='20160830';
      PARENT_PART_TYPE='Q_CAP';
      PARENT_PPT='Q_CAP';
      PARENT_PPT_PART='Q_CAP_C0603-4.7UF,25V,10%,X6S,CH5474KE906';
  end_body;
end_primitive;
primitive 'Q_CAP_C0805-10UF,25V,10%,X6S,CA';
  pin
    'A':
      PIN_NUMBER='(1)';
      PINUSE='UNSPEC';
      NO_LOAD_CHECK='BOTH';
      NO_IO_CHECK='BOTH';
      ALLOW_CONNECT='TRUE';
      PIN_GROUP='1';
    'B':
      PIN_NUMBER='(2)';
      PINUSE='UNSPEC';
      NO_LOAD_CHECK='BOTH';
      NO_IO_CHECK='BOTH';
      ALLOW_CONNECT='TRUE';
      PIN_GROUP='1';
  end_pin;
  body
      PART_NAME='Q_CAP';
      PHYS_DES_PREFIX='C';
      STANDARD='';
      LIFECYCLE='';
      ASS_PART='';
      JEDEC_TYPE='C0805_H61';
      ALT_SYMBOLS='(SMC0805AW)';
      VALUE='10UF';
      RATED_VOLTAGE='25V';
      TOL='10%';
      CLASS='DISCRETE';
      DESCRIPTION='CAP CHIP 10U 25V(+-10%,X6S,0805,H1.25)';
      COMPONENT_TYPE='CHIP0805';
      LEAD_LENGTH='';
      LPID='';
      DATE='20140327';
      PARENT_PART_TYPE='Q_CAP';
      PARENT_PPT='Q_CAP';
      PARENT_PPT_PART='Q_CAP_C0805-10UF,25V,10%,X6S,CH6104KEA00';
  end_body;
end_primitive;
primitive 'Q_CAP_C0805-22UF,10V,20%,X6S,CA';
  pin
    'A':
      PIN_NUMBER='(1)';
      PINUSE='UNSPEC';
      NO_LOAD_CHECK='BOTH';
      NO_IO_CHECK='BOTH';
      ALLOW_CONNECT='TRUE';
      PIN_GROUP='1';
    'B':
      PIN_NUMBER='(2)';
      PINUSE='UNSPEC';
      NO_LOAD_CHECK='BOTH';
      NO_IO_CHECK='BOTH';
      ALLOW_CONNECT='TRUE';
      PIN_GROUP='1';
  end_pin;
  body
      PART_NAME='Q_CAP';
      PHYS_DES_PREFIX='C';
      STANDARD='';
      LIFECYCLE='';
      ASS_PART='';
      JEDEC_TYPE='C0805_H61';
      ALT_SYMBOLS='(SMC0805AW)';
      VALUE='22UF';
      RATED_VOLTAGE='10V';
      TOL='20%';
      CLASS='DISCRETE';
      DESCRIPTION='CAP CHIP 22U 10V(+-20%,X6S,0805)';
      COMPONENT_TYPE='CHIP0805';
      LEAD_LENGTH='';
      LPID='';
      DATE='20150401';
      PARENT_PART_TYPE='Q_CAP';
      PARENT_PPT='Q_CAP';
      PARENT_PPT_PART='Q_CAP_C0805-22UF,10V,20%,X6S,CH6222MEA00';
  end_body;
end_primitive;
primitive 'Q_CAP_C0805-22UF,16V,20%,X6S,CA';
  pin
    'A':
      PIN_NUMBER='(1)';
      PINUSE='UNSPEC';
      NO_LOAD_CHECK='BOTH';
      NO_IO_CHECK='BOTH';
      ALLOW_CONNECT='TRUE';
      PIN_GROUP='1';
    'B':
      PIN_NUMBER='(2)';
      PINUSE='UNSPEC';
      NO_LOAD_CHECK='BOTH';
      NO_IO_CHECK='BOTH';
      ALLOW_CONNECT='TRUE';
      PIN_GROUP='1';
  end_pin;
  body
      PART_NAME='Q_CAP';
      PHYS_DES_PREFIX='C';
      STANDARD='';
      LIFECYCLE='';
      ASS_PART='';
      JEDEC_TYPE='C0805_H57';
      ALT_SYMBOLS='(SMC0805AW)';
      VALUE='22UF';
      RATED_VOLTAGE='16V';
      TOL='20%';
      CLASS='DISCRETE';
      DESCRIPTION='CAP CHIP 22UF 16V(+-20%,X6S,0805)MUR';
      COMPONENT_TYPE='CHIP0805';
      LEAD_LENGTH='';
      LPID='';
      DATE='20171127';
      PARENT_PART_TYPE='Q_CAP';
      PARENT_PPT='Q_CAP';
      PARENT_PPT_PART='Q_CAP_C0805-22UF,16V,20%,X6S,CH6223MEA01';
  end_body;
end_primitive;
primitive 'Q_CAP_C1206-47UF,6.3V,20%,X6S,A';
  pin
    'A':
      PIN_NUMBER='(1)';
      PINUSE='UNSPEC';
      NO_LOAD_CHECK='BOTH';
      NO_IO_CHECK='BOTH';
      ALLOW_CONNECT='TRUE';
      PIN_GROUP='1';
    'B':
      PIN_NUMBER='(2)';
      PINUSE='UNSPEC';
      NO_LOAD_CHECK='BOTH';
      NO_IO_CHECK='BOTH';
      ALLOW_CONNECT='TRUE';
      PIN_GROUP='1';
  end_pin;
  body
      PART_NAME='Q_CAP';
      PHYS_DES_PREFIX='C';
      STANDARD='End of Design';
      LIFECYCLE='Comp-Approve';
      ASS_PART='';
      JEDEC_TYPE='C1206_H76';
      ALT_SYMBOLS='(SMC1206AW)';
      VALUE='47UF';
      RATED_VOLTAGE='6.3V';
      TOL='20%';
      CLASS='DISCRETE';
      DESCRIPTION='CAP CHIP 47U 6.3V(+-20%,X6S,1206)';
      COMPONENT_TYPE='CHIP1206';
      LEAD_LENGTH='';
      LPID='';
      DATE='20151112';
      PARENT_PART_TYPE='Q_CAP';
      PARENT_PPT='Q_CAP';
      PARENT_PPT_PART='Q_CAP_C1206-47UF,6.3V,20%,X6S,CH6471ME200';
  end_body;
end_primitive;
primitive 'Q_DIODE_SMLF-SDMK0340L-7-F,EMPA';
  pin
    '1':
      PIN_NUMBER='(1)';
      INPUT_LOAD='(-0.01,0.01)';
      OUTPUT_LOAD='(1.0,-1.0)';
      BIDIRECTIONAL='TRUE';
      PINUSE='BI';
    '2':
      PIN_NUMBER='(2)';
      INPUT_LOAD='(-0.01,0.01)';
      OUTPUT_LOAD='(1.0,-1.0)';
      BIDIRECTIONAL='TRUE';
      PINUSE='BI';
  end_pin;
  body
      CLASS='IO';
      PART_NAME='Q_DIODE';
      PHYS_DES_PREFIX='D';
      STANDARD='';
      LIFECYCLE='';
      JEDEC_TYPE='SOD323XB';
      DESCRIPTION='DIODE SMD SDMK0340L-7-F(40V,30MA)';
      COMPONENT_TYPE='SMALLSMT';
      LEAD_LENGTH='';
      LPID='';
      DAY='20101005';
      PARENT_PART_TYPE='Q_DIODE';
      PARENT_PPT='Q_DIODE';
      PARENT_PPT_PART='Q_DIODE_SMLF-SDMK0340L-7-F,EMPTY,BC000340033';
  end_body;
end_primitive;
primitive 'Q_DIODE_SMLF-SDMK0340L-7-F,IC,A';
  pin
    '1':
      PIN_NUMBER='(1)';
      INPUT_LOAD='(-0.01,0.01)';
      OUTPUT_LOAD='(1.0,-1.0)';
      BIDIRECTIONAL='TRUE';
      PINUSE='BI';
    '2':
      PIN_NUMBER='(2)';
      INPUT_LOAD='(-0.01,0.01)';
      OUTPUT_LOAD='(1.0,-1.0)';
      BIDIRECTIONAL='TRUE';
      PINUSE='BI';
  end_pin;
  body
      CLASS='IC';
      PART_NAME='Q_DIODE';
      PHYS_DES_PREFIX='D';
      STANDARD='';
      LIFECYCLE='';
      JEDEC_TYPE='SOD323XB';
      DESCRIPTION='DIODE SMD SDMK0340L-7-F(40V,30MA)';
      COMPONENT_TYPE='SMALLSMT';
      LEAD_LENGTH='';
      LPID='';
      DAY='20101005';
      PARENT_PART_TYPE='Q_DIODE';
      PARENT_PPT='Q_DIODE';
      PARENT_PPT_PART='Q_DIODE_SMLF-SDMK0340L-7-F,IC,BC000340033';
  end_body;
end_primitive;
primitive 'Q_FUSE_SMLF-1.1A/8V,EMPTY,DK11A';
  pin
    '1':
      PIN_NUMBER='(1)';
      INPUT_LOAD='(-0.01,0.01)';
      OUTPUT_LOAD='(1.0,-1.0)';
      BIDIRECTIONAL='TRUE';
      PINUSE='BI';
    '2':
      PIN_NUMBER='(2)';
      INPUT_LOAD='(-0.01,0.01)';
      OUTPUT_LOAD='(1.0,-1.0)';
      BIDIRECTIONAL='TRUE';
      PINUSE='BI';
  end_pin;
  body
      CLASS='IO';
      PART_NAME='Q_FUSE';
      PHYS_DES_PREFIX='FS';
      STANDARD='';
      LIFECYCLE='';
      JEDEC_TYPE='F1206';
      DESCRIPTION='FUSE SMD 1.1A 8V POLY(SMD1206P110TFT)';
      COMPONENT_TYPE='CHIP';
      LEAD_LENGTH='';
      LPID='';
      DAY='20120915';
      PARENT_PART_TYPE='Q_FUSE';
      PARENT_PPT='Q_FUSE';
      PARENT_PPT_PART='Q_FUSE_SMLF-1.1A/8V,EMPTY,DK110TPU003';
  end_body;
end_primitive;
primitive 'Q_INDUCTOR4P_12-67/320MA,320MAA';
  pin
    '4':
      PIN_NUMBER='(4)';
      BIDIRECTIONAL='TRUE';
      INPUT_LOAD='(-0.01,0.01)';
      OUTPUT_LOAD='(1.0,-1.0)';
      PINUSE='BI';
    '3':
      PIN_NUMBER='(3)';
      BIDIRECTIONAL='TRUE';
      INPUT_LOAD='(-0.01,0.01)';
      OUTPUT_LOAD='(1.0,-1.0)';
      PINUSE='BI';
    '2':
      PIN_NUMBER='(2)';
      BIDIRECTIONAL='TRUE';
      INPUT_LOAD='(-0.01,0.01)';
      OUTPUT_LOAD='(1.0,-1.0)';
      PINUSE='BI';
    '1':
      PIN_NUMBER='(1)';
      BIDIRECTIONAL='TRUE';
      INPUT_LOAD='(-0.01,0.01)';
      OUTPUT_LOAD='(1.0,-1.0)';
      PINUSE='BI';
  end_pin;
  body
      PART_NAME='Q_INDUCTOR4P_12';
      BODY_NAME='Q_INDUCTOR4P_12';
      PHYS_DES_PREFIX='L';
      CLASS='DISCRETE';
      STANDARD='';
      LIFECYCLE='';
      JEDEC_TYPE='L_DLW21HNXA';
      DESCRIPTION='EMI FILTER DLW21SN670HQ2L(67,320MA)';
      MANUFTR='MUR';
      MANUF_PN='DLW21SN670HQ2L';
      RD_CMPLS_LVL='EU(V1)';
      CMPLS_LVL='';
      DIP_SMD='';
      FROM_PJ='T2A-TONY';
      DATA='MUR_DLW21S.pdf';
      FP_ECN='';
      EE_CHECK_LIST='';
      STATUS='';
      CREATOR='';
      CREATEDAY='20120604';
      PREFERENCE='';
      PSL='';
      PARENT_PART_TYPE='Q_INDUCTOR4P_12';
      PARENT_PPT='Q_INDUCTOR4P_12';
      PARENT_PPT_PART='Q_INDUCTOR4P_12-67/320MA,320MA,SMLF,EMPTY,CX21SN67000';
  end_body;
end_primitive;
primitive 'Q_INDUCTOR_SMLF-1UH,IND,CV-10BA';
  pin
    '2':
      PIN_NUMBER='(2)';
      BIDIRECTIONAL='TRUE';
      INPUT_LOAD='(-0.01,0.01)';
      OUTPUT_LOAD='(1.0,-1.0)';
      PINUSE='BI';
    '1':
      PIN_NUMBER='(1)';
      BIDIRECTIONAL='TRUE';
      INPUT_LOAD='(-0.01,0.01)';
      OUTPUT_LOAD='(1.0,-1.0)';
      PINUSE='BI';
  end_pin;
  body
      PART_NAME='Q_INDUCTOR';
      BODY_NAME='Q_INDUCTOR';
      PHYS_DES_PREFIX='L';
      CLASS='DISCRETE';
      STANDARD='';
      LIFECYCLE='';
      JEDEC_TYPE='L_PCMC063T';
      VALUE='1UH';
      DESCRIPTION='IND SMD 1UH 20%11A(PCMC063T-1R0MN)';
      COMPONENT_TYPE='CHIP';
      LEAD_LENGTH='';
      LPID='';
      DAY='20110221';
      PARENT_PART_TYPE='Q_INDUCTOR';
      PARENT_PPT='Q_INDUCTOR';
      PARENT_PPT_PART='Q_INDUCTOR_SMLF-1UH,IND,CV-10B0MZ13';
  end_body;
end_primitive;
primitive 'Q_INDUCTOR_SMLF-3.3UH/6A,IND,CA';
  pin
    '2':
      PIN_NUMBER='(2)';
      BIDIRECTIONAL='TRUE';
      INPUT_LOAD='(-0.01,0.01)';
      OUTPUT_LOAD='(1.0,-1.0)';
      PINUSE='BI';
    '1':
      PIN_NUMBER='(1)';
      BIDIRECTIONAL='TRUE';
      INPUT_LOAD='(-0.01,0.01)';
      OUTPUT_LOAD='(1.0,-1.0)';
      PINUSE='BI';
  end_pin;
  body
      PART_NAME='Q_INDUCTOR';
      BODY_NAME='Q_INDUCTOR';
      PHYS_DES_PREFIX='L';
      CLASS='DISCRETE';
      STANDARD='';
      LIFECYCLE='';
      JEDEC_TYPE='L_PCMC063T';
      VALUE='3.3UH/6A';
      DESCRIPTION='IND SMD 3.3UH,6A20%(PCMC063T-3R3MN)';
      COMPONENT_TYPE='CHIP';
      LEAD_LENGTH='';
      LPID='';
      DAY='20120921';
      PARENT_PART_TYPE='Q_INDUCTOR';
      PARENT_PPT='Q_INDUCTOR';
      PARENT_PPT_PART='Q_INDUCTOR_SMLF-3.3UH/6A,IND,CV-3360MZ07';
  end_body;
end_primitive;
primitive 'Q_INDUCTOR_SMLF-4.7UH,IND,CV-4A';
  pin
    '2':
      PIN_NUMBER='(2)';
      BIDIRECTIONAL='TRUE';
      INPUT_LOAD='(-0.01,0.01)';
      OUTPUT_LOAD='(1.0,-1.0)';
      PINUSE='BI';
    '1':
      PIN_NUMBER='(1)';
      BIDIRECTIONAL='TRUE';
      INPUT_LOAD='(-0.01,0.01)';
      OUTPUT_LOAD='(1.0,-1.0)';
      PINUSE='BI';
  end_pin;
  body
      PART_NAME='Q_INDUCTOR';
      BODY_NAME='Q_INDUCTOR';
      PHYS_DES_PREFIX='L';
      CLASS='DISCRETE';
      STANDARD='';
      LIFECYCLE='';
      JEDEC_TYPE='L_PCMB104EXB';
      VALUE='4.7UH';
      DESCRIPTION='IND SMD 4.7UH +-20% 10A(PCMB104E-4R7MS)';
      COMPONENT_TYPE='CHIP';
      LEAD_LENGTH='';
      LPID='';
      DAY='20110221';
      PARENT_PART_TYPE='Q_INDUCTOR';
      PARENT_PPT='Q_INDUCTOR';
      PARENT_PPT_PART='Q_INDUCTOR_SMLF-4.7UH,IND,CV-47A0MZ10';
  end_body;
end_primitive;
primitive 'Q_INDUCTOR_SMLF-BLM18BB470/500A';
  pin
    '2':
      PIN_NUMBER='(2)';
      BIDIRECTIONAL='TRUE';
      INPUT_LOAD='(-0.01,0.01)';
      OUTPUT_LOAD='(1.0,-1.0)';
      PINUSE='BI';
    '1':
      PIN_NUMBER='(1)';
      BIDIRECTIONAL='TRUE';
      INPUT_LOAD='(-0.01,0.01)';
      OUTPUT_LOAD='(1.0,-1.0)';
      PINUSE='BI';
  end_pin;
  body
      PART_NAME='Q_INDUCTOR';
      BODY_NAME='Q_INDUCTOR';
      PHYS_DES_PREFIX='L';
      CLASS='DISCRETE';
      STANDARD='';
      LIFECYCLE='';
      JEDEC_TYPE='L0603';
      VALUE='BLM18BB470/500MA';
      DESCRIPTION='EMI FILTER CHIP BLM18BB470(47.500MA)';
      COMPONENT_TYPE='CHIP';
      LEAD_LENGTH='';
      LPID='';
      DAY='20130704';
      PARENT_PART_TYPE='Q_INDUCTOR';
      PARENT_PPT='Q_INDUCTOR';
      PARENT_PPT_PART='Q_INDUCTOR_SMLF-BLM18BB470/500MA,IND,CX8BB470007';
  end_body;
end_primitive;
primitive 'Q_INDUCTOR_SMLF-BLM18EG121SN1DA';
  pin
    '2':
      PIN_NUMBER='(2)';
      BIDIRECTIONAL='TRUE';
      INPUT_LOAD='(-0.01,0.01)';
      OUTPUT_LOAD='(1.0,-1.0)';
      PINUSE='BI';
    '1':
      PIN_NUMBER='(1)';
      BIDIRECTIONAL='TRUE';
      INPUT_LOAD='(-0.01,0.01)';
      OUTPUT_LOAD='(1.0,-1.0)';
      PINUSE='BI';
  end_pin;
  body
      PART_NAME='Q_INDUCTOR';
      BODY_NAME='Q_INDUCTOR';
      PHYS_DES_PREFIX='L';
      CLASS='DISCRETE';
      STANDARD='';
      LIFECYCLE='';
      JEDEC_TYPE='L0603';
      VALUE='BLM18EG121SN1D/2A';
      DESCRIPTION='EMI FILTER BLM18EG121SN1D(120.2A)';
      COMPONENT_TYPE='CHIP';
      LEAD_LENGTH='';
      LPID='';
      DAY='20131016';
      PARENT_PART_TYPE='Q_INDUCTOR';
      PARENT_PPT='Q_INDUCTOR';
      PARENT_PPT_PART='Q_INDUCTOR_SMLF-BLM18EG121SN1D/2A,IND,CX8EG121000';
  end_body;
end_primitive;
primitive 'Q_INDUCTOR_SMLF-BLM18PG121SN1DA';
  pin
    '2':
      PIN_NUMBER='(2)';
      BIDIRECTIONAL='TRUE';
      INPUT_LOAD='(-0.01,0.01)';
      OUTPUT_LOAD='(1.0,-1.0)';
      PINUSE='BI';
    '1':
      PIN_NUMBER='(1)';
      BIDIRECTIONAL='TRUE';
      INPUT_LOAD='(-0.01,0.01)';
      OUTPUT_LOAD='(1.0,-1.0)';
      PINUSE='BI';
  end_pin;
  body
      PART_NAME='Q_INDUCTOR';
      BODY_NAME='Q_INDUCTOR';
      PHYS_DES_PREFIX='L';
      CLASS='DISCRETE';
      STANDARD='';
      LIFECYCLE='';
      JEDEC_TYPE='L0603';
      VALUE='BLM18PG121SN1D/2000MA';
      DESCRIPTION='EMI FILTER BLM18PG121SN(120,2000MA)';
      COMPONENT_TYPE='CHIP';
      LEAD_LENGTH='';
      LPID='';
      DAY='20140812';
      PARENT_PART_TYPE='Q_INDUCTOR';
      PARENT_PPT='Q_INDUCTOR';
      PARENT_PPT_PART='Q_INDUCTOR_SMLF-BLM18PG121SN1D/2000MA,IND,CX8PG121009';
  end_body;
end_primitive;
primitive 'Q_INDUCTOR_SMLF-BLM18PG121SN1DB';
  pin
    '2':
      PIN_NUMBER='(2)';
      BIDIRECTIONAL='TRUE';
      INPUT_LOAD='(-0.01,0.01)';
      OUTPUT_LOAD='(1.0,-1.0)';
      PINUSE='BI';
    '1':
      PIN_NUMBER='(1)';
      BIDIRECTIONAL='TRUE';
      INPUT_LOAD='(-0.01,0.01)';
      OUTPUT_LOAD='(1.0,-1.0)';
      PINUSE='BI';
  end_pin;
  body
      PART_NAME='Q_INDUCTOR';
      BODY_NAME='Q_INDUCTOR';
      PHYS_DES_PREFIX='L';
      CLASS='IO';
      STANDARD='';
      LIFECYCLE='';
      JEDEC_TYPE='L0603';
      VALUE='NA';
      DESCRIPTION='EMI FILTER BLM18PG121SN(120,2000MA)';
      COMPONENT_TYPE='CHIP';
      LEAD_LENGTH='';
      LPID='';
      DAY='20140812';
      PARENT_PART_TYPE='Q_INDUCTOR';
      PARENT_PPT='Q_INDUCTOR';
      PARENT_PPT_PART='Q_INDUCTOR_SMLF-BLM18PG121SN1D/2000MA,EMPTY,CX8PG121009';
  end_body;
end_primitive;
primitive 'Q_INDUCTOR_SMLF-BLM18SN220TN1DA';
  pin
    '2':
      PIN_NUMBER='(2)';
      BIDIRECTIONAL='TRUE';
      INPUT_LOAD='(-0.01,0.01)';
      OUTPUT_LOAD='(1.0,-1.0)';
      PINUSE='BI';
    '1':
      PIN_NUMBER='(1)';
      BIDIRECTIONAL='TRUE';
      INPUT_LOAD='(-0.01,0.01)';
      OUTPUT_LOAD='(1.0,-1.0)';
      PINUSE='BI';
  end_pin;
  body
      PART_NAME='Q_INDUCTOR';
      BODY_NAME='Q_INDUCTOR';
      PHYS_DES_PREFIX='L';
      CLASS='DISCRETE';
      STANDARD='End of Design';
      LIFECYCLE='Comp-Approve';
      JEDEC_TYPE='L0603';
      VALUE='BLM18SN220TN1D/8000MA';
      DESCRIPTION='EMI FILTER BLM18SN220TN1D(22,8000MA)';
      COMPONENT_TYPE='CHIP';
      LEAD_LENGTH='';
      LPID='';
      DAY='20160104';
      PARENT_PART_TYPE='Q_INDUCTOR';
      PARENT_PPT='Q_INDUCTOR';
      PARENT_PPT_PART='Q_INDUCTOR_SMLF-BLM18SN220TN1D/8000MA,IND,CX220TN1001';
  end_body;
end_primitive;
primitive 'Q_LED_SMLF-LED_BLUE,LTST-C281TA';
  pin
    'A':
      PIN_NUMBER='(A)';
      INPUT_LOAD='(-0.01,0.01)';
      OUTPUT_LOAD='(1.0,-1.0)';
      BIDIRECTIONAL='TRUE';
      PINUSE='BI';
    'C':
      PIN_NUMBER='(C)';
      INPUT_LOAD='(-0.01,0.01)';
      OUTPUT_LOAD='(1.0,-1.0)';
      BIDIRECTIONAL='TRUE';
      PINUSE='BI';
  end_pin;
  body
      CLASS='IC';
      PART_NAME='Q_LED';
      PHYS_DES_PREFIX='D';
      STANDARD='';
      LIFECYCLE='';
      JEDEC_TYPE='LED2S_0402';
      DESCRIPTION='LED SMD(2P) BLUE(LTST-C281TBKT-5A)';
      COMPONENT_TYPE='';
      LEAD_LENGTH='';
      LPID='';
      DAY='20121120';
      PARENT_PART_TYPE='Q_LED';
      PARENT_PPT='Q_LED';
      PARENT_PPT_PART='Q_LED_SMLF-LED_BLUE,LTST-C281TBKT-5A,IC,BEBL0172Z00';
  end_body;
end_primitive;
primitive 'Q_LED_SMLF-LED_GREEN,19-213/GVA';
  pin
    'A':
      PIN_NUMBER='(A)';
      INPUT_LOAD='(-0.01,0.01)';
      OUTPUT_LOAD='(1.0,-1.0)';
      BIDIRECTIONAL='TRUE';
      PINUSE='BI';
    'C':
      PIN_NUMBER='(C)';
      INPUT_LOAD='(-0.01,0.01)';
      OUTPUT_LOAD='(1.0,-1.0)';
      BIDIRECTIONAL='TRUE';
      PINUSE='BI';
  end_pin;
  body
      CLASS='IC';
      PART_NAME='Q_LED';
      PHYS_DES_PREFIX='D';
      STANDARD='';
      LIFECYCLE='';
      JEDEC_TYPE='LED_1921';
      DESCRIPTION='LED SMD(2P) GREEN(19-213/GVC-AMNB/3T)';
      COMPONENT_TYPE='';
      LEAD_LENGTH='';
      LPID='';
      DAY='20150305';
      PARENT_PART_TYPE='Q_LED';
      PARENT_PPT='Q_LED';
      PARENT_PPT_PART='Q_LED_SMLF-LED_GREEN,19-213/GVC-AMNB/3T,IC,BEGR0278Z00';
  end_body;
end_primitive;
primitive 'Q_LED_SMLF-LED_RED,19-217/R6C-A';
  pin
    'A':
      PIN_NUMBER='(A)';
      INPUT_LOAD='(-0.01,0.01)';
      OUTPUT_LOAD='(1.0,-1.0)';
      BIDIRECTIONAL='TRUE';
      PINUSE='BI';
    'C':
      PIN_NUMBER='(C)';
      INPUT_LOAD='(-0.01,0.01)';
      OUTPUT_LOAD='(1.0,-1.0)';
      BIDIRECTIONAL='TRUE';
      PINUSE='BI';
  end_pin;
  body
      CLASS='IC';
      PART_NAME='Q_LED';
      PHYS_DES_PREFIX='D';
      STANDARD='';
      LIFECYCLE='';
      JEDEC_TYPE='LED_19217';
      DESCRIPTION='LED SMD(2P) RED (19-217/R6C-P1Q2/3T)';
      COMPONENT_TYPE='';
      LEAD_LENGTH='';
      LPID='';
      DAY='20150203';
      PARENT_PART_TYPE='Q_LED';
      PARENT_PPT='Q_LED';
      PARENT_PPT_PART='Q_LED_SMLF-LED_RED,19-217/R6C-P1Q2/3T,IC,BERD0034Z07';
  end_body;
end_primitive;
primitive 'Q_LED_THLF-LED_BLUE,HV-312470/A';
  pin
    'A':
      PIN_NUMBER='(A)';
      INPUT_LOAD='(-0.01,0.01)';
      OUTPUT_LOAD='(1.0,-1.0)';
      BIDIRECTIONAL='TRUE';
      PINUSE='BI';
    'C':
      PIN_NUMBER='(C)';
      INPUT_LOAD='(-0.01,0.01)';
      OUTPUT_LOAD='(1.0,-1.0)';
      BIDIRECTIONAL='TRUE';
      PINUSE='BI';
  end_pin;
  body
      CLASS='IC';
      PART_NAME='Q_LED';
      PHYS_DES_PREFIX='D';
      STANDARD='';
      LIFECYCLE='';
      JEDEC_TYPE='LED2P_HV-312470260';
      DESCRIPTION='LED DIP(2P)BLUE(HV-312470/260/SUBD-TR1)';
      COMPONENT_TYPE='';
      LEAD_LENGTH='';
      LPID='';
      DAY='20220818';
      PARENT_PART_TYPE='Q_LED';
      PARENT_PPT='Q_LED';
      PARENT_PPT_PART='Q_LED_THLF-LED_BLUE,HV-312470/260/SUBD-TR1,IC,BEBL0277D00';
  end_body;
end_primitive;
primitive 'Q_LED_THLF-LED_YELLOW,LTL-R42FA';
  pin
    'A':
      PIN_NUMBER='(A)';
      INPUT_LOAD='(-0.01,0.01)';
      OUTPUT_LOAD='(1.0,-1.0)';
      BIDIRECTIONAL='TRUE';
      PINUSE='BI';
    'C':
      PIN_NUMBER='(C)';
      INPUT_LOAD='(-0.01,0.01)';
      OUTPUT_LOAD='(1.0,-1.0)';
      BIDIRECTIONAL='TRUE';
      PINUSE='BI';
  end_pin;
  body
      CLASS='IC';
      PART_NAME='Q_LED';
      PHYS_DES_PREFIX='D';
      STANDARD='';
      LIFECYCLE='';
      JEDEC_TYPE='LED2P_LTL-R42FSFADH213T';
      DESCRIPTION='LED DIP(2P)YELLOW(LTL-R42FSFADH213T)';
      COMPONENT_TYPE='';
      LEAD_LENGTH='';
      LPID='';
      DAY='20220830';
      PARENT_PART_TYPE='Q_LED';
      PARENT_PPT='Q_LED';
      PARENT_PPT_PART='Q_LED_THLF-LED_YELLOW,LTL-R42FSFADH213T,IC,BEYL0182D00';
  end_body;
end_primitive;
primitive 'Q_RES_0402LF-0,5%,1/16W,CHIP,CA';
  pin
    'A':
      PIN_GROUP='1';
      PIN_NUMBER='(1)';
      PIN_TYPE='UNSPEC';
      PINUSE='UNSPEC';
    'B':
      PIN_GROUP='1';
      PIN_NUMBER='(2)';
      PIN_TYPE='UNSPEC';
      PINUSE='UNSPEC';
  end_pin;
  body
      PART_NAME='Q_RES';
      PHYS_DES_PREFIX='R';
      STANDARD='End of Design';
      LIFECYCLE='Comp-Approve';
      JEDEC_TYPE='R0402';
      ALT_SYMBOLS='(R0402-0201)';
      VALUE='0';
      TOL='5%';
      WATTAGE='1/16W';
      CLASS='DISCRETE';
      DESCRIPTION='RES CHIP 0 1/16W +-5%(0402)EF';
      COMPONENT_TYPE='CHIPR0402';
      LEAD_LENGTH='';
      DFM_EXCLUSION='';
      DAY='20180208';
      PARENT_PART_TYPE='Q_RES';
      PARENT_PPT='Q_RES';
      PARENT_PPT_PART='Q_RES_0402LF-0,5%,1/16W,CHIP,CS00002JB13';
  end_body;
end_primitive;
primitive 'Q_RES_0402LF-0,5%,1/16W,EMPTY,A';
  pin
    'A':
      PIN_GROUP='1';
      PIN_NUMBER='(1)';
      PIN_TYPE='UNSPEC';
      PINUSE='UNSPEC';
    'B':
      PIN_GROUP='1';
      PIN_NUMBER='(2)';
      PIN_TYPE='UNSPEC';
      PINUSE='UNSPEC';
  end_pin;
  body
      PART_NAME='Q_RES';
      PHYS_DES_PREFIX='R';
      STANDARD='End of Design';
      LIFECYCLE='Comp-Approve';
      JEDEC_TYPE='R0402';
      ALT_SYMBOLS='(R0402-0201)';
      VALUE='0';
      TOL='5%';
      WATTAGE='1/16W';
      CLASS='IO';
      DESCRIPTION='RES CHIP 0 1/16W +-5%(0402)EF';
      COMPONENT_TYPE='CHIPR0402';
      LEAD_LENGTH='';
      DFM_EXCLUSION='';
      DAY='20180208';
      PARENT_PART_TYPE='Q_RES';
      PARENT_PPT='Q_RES';
      PARENT_PPT_PART='Q_RES_0402LF-0,5%,1/16W,EMPTY,CS00002JB13';
  end_body;
end_primitive;
primitive 'Q_RES_0402LF-1.69K,1%,1/16W,CHA';
  pin
    'A':
      PIN_GROUP='1';
      PIN_NUMBER='(1)';
      PIN_TYPE='UNSPEC';
      PINUSE='UNSPEC';
    'B':
      PIN_GROUP='1';
      PIN_NUMBER='(2)';
      PIN_TYPE='UNSPEC';
      PINUSE='UNSPEC';
  end_pin;
  body
      PART_NAME='Q_RES';
      PHYS_DES_PREFIX='R';
      STANDARD='End of Design';
      LIFECYCLE='Comp-Approve';
      JEDEC_TYPE='R0402';
      ALT_SYMBOLS='(R0402-0201)';
      VALUE='1.69K';
      TOL='1%';
      WATTAGE='1/16W';
      CLASS='DISCRETE';
      DESCRIPTION='RES CHIP 1.69K 1/16W +-1%(0402)EF';
      COMPONENT_TYPE='CHIPR0402';
      LEAD_LENGTH='';
      DFM_EXCLUSION='';
      DAY='20210804';
      PARENT_PART_TYPE='Q_RES';
      PARENT_PPT='Q_RES';
      PARENT_PPT_PART='Q_RES_0402LF-1.69K,1%,1/16W,CHIP,CS21692FB04';
  end_body;
end_primitive;
primitive 'Q_RES_0402LF-1.8K,1%,1/16W,CHIA';
  pin
    'A':
      PIN_GROUP='1';
      PIN_NUMBER='(1)';
      PIN_TYPE='UNSPEC';
      PINUSE='UNSPEC';
    'B':
      PIN_GROUP='1';
      PIN_NUMBER='(2)';
      PIN_TYPE='UNSPEC';
      PINUSE='UNSPEC';
  end_pin;
  body
      PART_NAME='Q_RES';
      PHYS_DES_PREFIX='R';
      STANDARD='End of Design';
      LIFECYCLE='Comp-Approve';
      JEDEC_TYPE='R0402';
      ALT_SYMBOLS='(R0402-0201)';
      VALUE='1.8K';
      TOL='1%';
      WATTAGE='1/16W';
      CLASS='DISCRETE';
      DESCRIPTION='RES CHIP 1.8K 1/16W +-1%(0402)';
      COMPONENT_TYPE='CHIP0402';
      LEAD_LENGTH='';
      DFM_EXCLUSION='';
      DAY='20140630';
      PARENT_PART_TYPE='Q_RES';
      PARENT_PPT='Q_RES';
      PARENT_PPT_PART='Q_RES_0402LF-1.8K,1%,1/16W,CHIP,CS21802FB10';
  end_body;
end_primitive;
primitive 'Q_RES_0402LF-10,1%,1/16W,CHIP,A';
  pin
    'A':
      PIN_GROUP='1';
      PIN_NUMBER='(1)';
      PIN_TYPE='UNSPEC';
      PINUSE='UNSPEC';
    'B':
      PIN_GROUP='1';
      PIN_NUMBER='(2)';
      PIN_TYPE='UNSPEC';
      PINUSE='UNSPEC';
  end_pin;
  body
      PART_NAME='Q_RES';
      PHYS_DES_PREFIX='R';
      STANDARD='End of Design';
      LIFECYCLE='Comp-Approve';
      JEDEC_TYPE='R0402';
      ALT_SYMBOLS='(R0402-0201)';
      VALUE='10';
      TOL='1%';
      WATTAGE='1/16W';
      CLASS='DISCRETE';
      DESCRIPTION='RES CHIP 10 1/16W +-1%(0402)EF';
      COMPONENT_TYPE='CHIPR0402';
      LEAD_LENGTH='';
      DFM_EXCLUSION='';
      DAY='20180208';
      PARENT_PART_TYPE='Q_RES';
      PARENT_PPT='Q_RES';
      PARENT_PPT_PART='Q_RES_0402LF-10,1%,1/16W,CHIP,CS01002FB07';
  end_body;
end_primitive;
primitive 'Q_RES_0402LF-100,1%,1/16W,CHIPA';
  pin
    'A':
      PIN_GROUP='1';
      PIN_NUMBER='(1)';
      PIN_TYPE='UNSPEC';
      PINUSE='UNSPEC';
    'B':
      PIN_GROUP='1';
      PIN_NUMBER='(2)';
      PIN_TYPE='UNSPEC';
      PINUSE='UNSPEC';
  end_pin;
  body
      PART_NAME='Q_RES';
      PHYS_DES_PREFIX='R';
      STANDARD='End of Design';
      LIFECYCLE='Comp-Approve';
      JEDEC_TYPE='R0402';
      ALT_SYMBOLS='(R0402-0201)';
      VALUE='100';
      TOL='1%';
      WATTAGE='1/16W';
      CLASS='DISCRETE';
      DESCRIPTION='RES CHIP 100 1/16W +-1%(0402)EF';
      COMPONENT_TYPE='CHIPR0402';
      LEAD_LENGTH='';
      DFM_EXCLUSION='';
      DAY='20180208';
      PARENT_PART_TYPE='Q_RES';
      PARENT_PPT='Q_RES';
      PARENT_PPT_PART='Q_RES_0402LF-100,1%,1/16W,CHIP,CS11002FB07';
  end_body;
end_primitive;
primitive 'Q_RES_0402LF-100,1%,1/16W,EMPTA';
  pin
    'A':
      PIN_GROUP='1';
      PIN_NUMBER='(1)';
      PIN_TYPE='UNSPEC';
      PINUSE='UNSPEC';
    'B':
      PIN_GROUP='1';
      PIN_NUMBER='(2)';
      PIN_TYPE='UNSPEC';
      PINUSE='UNSPEC';
  end_pin;
  body
      PART_NAME='Q_RES';
      PHYS_DES_PREFIX='R';
      STANDARD='End of Design';
      LIFECYCLE='Comp-Approve';
      JEDEC_TYPE='R0402';
      ALT_SYMBOLS='(R0402-0201)';
      VALUE='100';
      TOL='1%';
      WATTAGE='1/16W';
      CLASS='IO';
      DESCRIPTION='RES CHIP 100 1/16W +-1%(0402)EF';
      COMPONENT_TYPE='CHIPR0402';
      LEAD_LENGTH='';
      DFM_EXCLUSION='';
      DAY='20180208';
      PARENT_PART_TYPE='Q_RES';
      PARENT_PPT='Q_RES';
      PARENT_PPT_PART='Q_RES_0402LF-100,1%,1/16W,EMPTY,CS11002FB07';
  end_body;
end_primitive;
primitive 'Q_RES_0402LF-100K,1%,1/16W,CHIA';
  pin
    'A':
      PIN_GROUP='1';
      PIN_NUMBER='(1)';
      PIN_TYPE='UNSPEC';
      PINUSE='UNSPEC';
    'B':
      PIN_GROUP='1';
      PIN_NUMBER='(2)';
      PIN_TYPE='UNSPEC';
      PINUSE='UNSPEC';
  end_pin;
  body
      PART_NAME='Q_RES';
      PHYS_DES_PREFIX='R';
      STANDARD='End of Design';
      LIFECYCLE='Comp-Approve';
      JEDEC_TYPE='R0402';
      ALT_SYMBOLS='(R0402-0201)';
      VALUE='100K';
      TOL='1%';
      WATTAGE='1/16W';
      CLASS='DISCRETE';
      DESCRIPTION='RES CHIP 100K 1/16W +-1%(0402)EF';
      COMPONENT_TYPE='CHIPR0402';
      LEAD_LENGTH='';
      DFM_EXCLUSION='';
      DAY='20180208';
      PARENT_PART_TYPE='Q_RES';
      PARENT_PPT='Q_RES';
      PARENT_PPT_PART='Q_RES_0402LF-100K,1%,1/16W,CHIP,CS41002FB09';
  end_body;
end_primitive;
primitive 'Q_RES_0402LF-100K,1%,1/16W,EMPA';
  pin
    'A':
      PIN_GROUP='1';
      PIN_NUMBER='(1)';
      PIN_TYPE='UNSPEC';
      PINUSE='UNSPEC';
    'B':
      PIN_GROUP='1';
      PIN_NUMBER='(2)';
      PIN_TYPE='UNSPEC';
      PINUSE='UNSPEC';
  end_pin;
  body
      PART_NAME='Q_RES';
      PHYS_DES_PREFIX='R';
      STANDARD='End of Design';
      LIFECYCLE='Comp-Approve';
      JEDEC_TYPE='R0402';
      ALT_SYMBOLS='(R0402-0201)';
      VALUE='100K';
      TOL='1%';
      WATTAGE='1/16W';
      CLASS='IO';
      DESCRIPTION='RES CHIP 100K 1/16W +-1%(0402)EF';
      COMPONENT_TYPE='CHIPR0402';
      LEAD_LENGTH='';
      DFM_EXCLUSION='';
      DAY='20180208';
      PARENT_PART_TYPE='Q_RES';
      PARENT_PPT='Q_RES';
      PARENT_PPT_PART='Q_RES_0402LF-100K,1%,1/16W,EMPTY,CS41002FB09';
  end_body;
end_primitive;
primitive 'Q_RES_0402LF-10K,1%,1/16W,CHIPA';
  pin
    'A':
      PIN_GROUP='1';
      PIN_NUMBER='(1)';
      PIN_TYPE='UNSPEC';
      PINUSE='UNSPEC';
    'B':
      PIN_GROUP='1';
      PIN_NUMBER='(2)';
      PIN_TYPE='UNSPEC';
      PINUSE='UNSPEC';
  end_pin;
  body
      PART_NAME='Q_RES';
      PHYS_DES_PREFIX='R';
      STANDARD='End of Design';
      LIFECYCLE='Comp-Approve';
      JEDEC_TYPE='R0402';
      ALT_SYMBOLS='(R0402-0201)';
      VALUE='10K';
      TOL='1%';
      WATTAGE='1/16W';
      CLASS='DISCRETE';
      DESCRIPTION='RES CHIP 10K 1/16W +-1%(0402)EF';
      COMPONENT_TYPE='CHIPR0402';
      LEAD_LENGTH='';
      DFM_EXCLUSION='';
      DAY='20180208';
      PARENT_PART_TYPE='Q_RES';
      PARENT_PPT='Q_RES';
      PARENT_PPT_PART='Q_RES_0402LF-10K,1%,1/16W,CHIP,CS31002FB08';
  end_body;
end_primitive;
primitive 'Q_RES_0402LF-10K,1%,1/16W,EMPTA';
  pin
    'A':
      PIN_GROUP='1';
      PIN_NUMBER='(1)';
      PIN_TYPE='UNSPEC';
      PINUSE='UNSPEC';
    'B':
      PIN_GROUP='1';
      PIN_NUMBER='(2)';
      PIN_TYPE='UNSPEC';
      PINUSE='UNSPEC';
  end_pin;
  body
      PART_NAME='Q_RES';
      PHYS_DES_PREFIX='R';
      STANDARD='End of Design';
      LIFECYCLE='Comp-Approve';
      JEDEC_TYPE='R0402';
      ALT_SYMBOLS='(R0402-0201)';
      VALUE='10K';
      TOL='1%';
      WATTAGE='1/16W';
      CLASS='IO';
      DESCRIPTION='RES CHIP 10K 1/16W +-1%(0402)EF';
      COMPONENT_TYPE='CHIPR0402';
      LEAD_LENGTH='';
      DFM_EXCLUSION='';
      DAY='20180208';
      PARENT_PART_TYPE='Q_RES';
      PARENT_PPT='Q_RES';
      PARENT_PPT_PART='Q_RES_0402LF-10K,1%,1/16W,EMPTY,CS31002FB08';
  end_body;
end_primitive;
primitive 'Q_RES_0402LF-10K,1%,1/16W,EMPTB';
  pin
    'A':
      PIN_GROUP='1';
      PIN_NUMBER='(1)';
      PIN_TYPE='UNSPEC';
      PINUSE='UNSPEC';
    'B':
      PIN_GROUP='1';
      PIN_NUMBER='(2)';
      PIN_TYPE='UNSPEC';
      PINUSE='UNSPEC';
  end_pin;
  body
      PART_NAME='Q_RES';
      PHYS_DES_PREFIX='R';
      STANDARD='End of Design';
      LIFECYCLE='Comp-Approve';
      JEDEC_TYPE='R0402';
      ALT_SYMBOLS='(R0402-0201)';
      VALUE='10K';
      TOL='1%';
      WATTAGE='1/16W';
      CLASS='IO';
      DESCRIPTION='RES CHIP 10K 1/16W +-1% (0402)';
      COMPONENT_TYPE='CHIP0402';
      LEAD_LENGTH='';
      DFM_EXCLUSION='';
      DAY='';
      PARENT_PART_TYPE='Q_RES';
      PARENT_PPT='Q_RES';
      PARENT_PPT_PART='Q_RES_0402LF-10K,1%,1/16W,EMPTY,TMP_QCS31002FB26';
  end_body;
end_primitive;
primitive 'Q_RES_0402LF-110,1%,1/16W,CHIPA';
  pin
    'A':
      PIN_GROUP='1';
      PIN_NUMBER='(1)';
      PIN_TYPE='UNSPEC';
      PINUSE='UNSPEC';
    'B':
      PIN_GROUP='1';
      PIN_NUMBER='(2)';
      PIN_TYPE='UNSPEC';
      PINUSE='UNSPEC';
  end_pin;
  body
      PART_NAME='Q_RES';
      PHYS_DES_PREFIX='R';
      STANDARD='';
      LIFECYCLE='';
      JEDEC_TYPE='R0402';
      ALT_SYMBOLS='(R0402-0201)';
      VALUE='110';
      TOL='1%';
      WATTAGE='1/16W';
      CLASS='DISCRETE';
      DESCRIPTION='RES CHIP 110 1/16W +-1%(0402)EF';
      COMPONENT_TYPE='CHIPR0402';
      LEAD_LENGTH='';
      DFM_EXCLUSION='';
      DAY='20220316';
      PARENT_PART_TYPE='Q_RES';
      PARENT_PPT='Q_RES';
      PARENT_PPT_PART='Q_RES_0402LF-110,1%,1/16W,CHIP,CS11102FB03';
  end_body;
end_primitive;
primitive 'Q_RES_0402LF-12.4K,1%,1/16W,CHA';
  pin
    'A':
      PIN_GROUP='1';
      PIN_NUMBER='(1)';
      PIN_TYPE='UNSPEC';
      PINUSE='UNSPEC';
    'B':
      PIN_GROUP='1';
      PIN_NUMBER='(2)';
      PIN_TYPE='UNSPEC';
      PINUSE='UNSPEC';
  end_pin;
  body
      PART_NAME='Q_RES';
      PHYS_DES_PREFIX='R';
      STANDARD='End of Design';
      LIFECYCLE='Comp-Approve';
      JEDEC_TYPE='R0402';
      ALT_SYMBOLS='(R0402-0201)';
      VALUE='12.4K';
      TOL='1%';
      WATTAGE='1/16W';
      CLASS='DISCRETE';
      DESCRIPTION='RES CHIP 12.4K 1/16W +-1%(0402)EF';
      COMPONENT_TYPE='CHIPR0402';
      LEAD_LENGTH='';
      DFM_EXCLUSION='';
      DAY='20180221';
      PARENT_PART_TYPE='Q_RES';
      PARENT_PPT='Q_RES';
      PARENT_PPT_PART='Q_RES_0402LF-12.4K,1%,1/16W,CHIP,CS31242FB02';
  end_body;
end_primitive;
primitive 'Q_RES_0402LF-120,1%,1/16W,CHIPA';
  pin
    'A':
      PIN_GROUP='1';
      PIN_NUMBER='(1)';
      PIN_TYPE='UNSPEC';
      PINUSE='UNSPEC';
    'B':
      PIN_GROUP='1';
      PIN_NUMBER='(2)';
      PIN_TYPE='UNSPEC';
      PINUSE='UNSPEC';
  end_pin;
  body
      PART_NAME='Q_RES';
      PHYS_DES_PREFIX='R';
      STANDARD='End of Design';
      LIFECYCLE='Comp-Approve';
      JEDEC_TYPE='R0402';
      ALT_SYMBOLS='(R0402-0201)';
      VALUE='120';
      TOL='1%';
      WATTAGE='1/16W';
      CLASS='DISCRETE';
      DESCRIPTION='RES CHIP 120 1/16W +-1%(0402)EF';
      COMPONENT_TYPE='CHIPR0402';
      LEAD_LENGTH='';
      DFM_EXCLUSION='';
      DAY='20180116';
      PARENT_PART_TYPE='Q_RES';
      PARENT_PPT='Q_RES';
      PARENT_PPT_PART='Q_RES_0402LF-120,1%,1/16W,CHIP,CS11202FB02';
  end_body;
end_primitive;
primitive 'Q_RES_0402LF-120,1%,1/16W,EMPTA';
  pin
    'A':
      PIN_GROUP='1';
      PIN_NUMBER='(1)';
      PIN_TYPE='UNSPEC';
      PINUSE='UNSPEC';
    'B':
      PIN_GROUP='1';
      PIN_NUMBER='(2)';
      PIN_TYPE='UNSPEC';
      PINUSE='UNSPEC';
  end_pin;
  body
      PART_NAME='Q_RES';
      PHYS_DES_PREFIX='R';
      STANDARD='End of Design';
      LIFECYCLE='Comp-Approve';
      JEDEC_TYPE='R0402';
      ALT_SYMBOLS='(R0402-0201)';
      VALUE='120';
      TOL='1%';
      WATTAGE='1/16W';
      CLASS='IO';
      DESCRIPTION='RES CHIP 120 1/16W +-1%(0402)EF';
      COMPONENT_TYPE='CHIPR0402';
      LEAD_LENGTH='';
      DFM_EXCLUSION='';
      DAY='20180116';
      PARENT_PART_TYPE='Q_RES';
      PARENT_PPT='Q_RES';
      PARENT_PPT_PART='Q_RES_0402LF-120,1%,1/16W,EMPTY,CS11202FB02';
  end_body;
end_primitive;
primitive 'Q_RES_0402LF-12K,1%,1/16W,CHIPA';
  pin
    'A':
      PIN_GROUP='1';
      PIN_NUMBER='(1)';
      PIN_TYPE='UNSPEC';
      PINUSE='UNSPEC';
    'B':
      PIN_GROUP='1';
      PIN_NUMBER='(2)';
      PIN_TYPE='UNSPEC';
      PINUSE='UNSPEC';
  end_pin;
  body
      PART_NAME='Q_RES';
      PHYS_DES_PREFIX='R';
      STANDARD='End of Design';
      LIFECYCLE='Comp-Approve';
      JEDEC_TYPE='R0402';
      ALT_SYMBOLS='(R0402-0201)';
      VALUE='12K';
      TOL='1%';
      WATTAGE='1/16W';
      CLASS='DISCRETE';
      DESCRIPTION='RES CHIP 12K 1/16W +-1%(0402)EF';
      COMPONENT_TYPE='CHIPR0402';
      LEAD_LENGTH='';
      DFM_EXCLUSION='';
      DAY='20180221';
      PARENT_PART_TYPE='Q_RES';
      PARENT_PPT='Q_RES';
      PARENT_PPT_PART='Q_RES_0402LF-12K,1%,1/16W,CHIP,CS31202FB04';
  end_body;
end_primitive;
primitive 'Q_RES_0402LF-15.8K,1%,1/16W,CHA';
  pin
    'A':
      PIN_GROUP='1';
      PIN_NUMBER='(1)';
      PIN_TYPE='UNSPEC';
      PINUSE='UNSPEC';
    'B':
      PIN_GROUP='1';
      PIN_NUMBER='(2)';
      PIN_TYPE='UNSPEC';
      PINUSE='UNSPEC';
  end_pin;
  body
      PART_NAME='Q_RES';
      PHYS_DES_PREFIX='R';
      STANDARD='End of Design';
      LIFECYCLE='Comp-Approve';
      JEDEC_TYPE='R0402';
      ALT_SYMBOLS='(R0402-0201)';
      VALUE='15.8K';
      TOL='1%';
      WATTAGE='1/16W';
      CLASS='DISCRETE';
      DESCRIPTION='RES CHIP 15.8K 1/16W +-1% (0402)EF';
      COMPONENT_TYPE='CHIPR0402';
      LEAD_LENGTH='';
      DFM_EXCLUSION='';
      DAY='20180221';
      PARENT_PART_TYPE='Q_RES';
      PARENT_PPT='Q_RES';
      PARENT_PPT_PART='Q_RES_0402LF-15.8K,1%,1/16W,CHIP,CS31582FB02';
  end_body;
end_primitive;
primitive 'Q_RES_0402LF-150,1%,1/16W,CHIPA';
  pin
    'A':
      PIN_GROUP='1';
      PIN_NUMBER='(1)';
      PIN_TYPE='UNSPEC';
      PINUSE='UNSPEC';
    'B':
      PIN_GROUP='1';
      PIN_NUMBER='(2)';
      PIN_TYPE='UNSPEC';
      PINUSE='UNSPEC';
  end_pin;
  body
      PART_NAME='Q_RES';
      PHYS_DES_PREFIX='R';
      STANDARD='End of Design';
      LIFECYCLE='Comp-Approve';
      JEDEC_TYPE='R0402';
      ALT_SYMBOLS='(R0402-0201)';
      VALUE='150';
      TOL='1%';
      WATTAGE='1/16W';
      CLASS='DISCRETE';
      DESCRIPTION='RES CHIP 150 1/16W +-1%(0402)EF';
      COMPONENT_TYPE='CHIPR0402';
      LEAD_LENGTH='';
      DFM_EXCLUSION='';
      DAY='20180208';
      PARENT_PART_TYPE='Q_RES';
      PARENT_PPT='Q_RES';
      PARENT_PPT_PART='Q_RES_0402LF-150,1%,1/16W,CHIP,CS11502FB07';
  end_body;
end_primitive;
primitive 'Q_RES_0402LF-150K,1%,1/16W,CHIA';
  pin
    'A':
      PIN_GROUP='1';
      PIN_NUMBER='(1)';
      PIN_TYPE='UNSPEC';
      PINUSE='UNSPEC';
    'B':
      PIN_GROUP='1';
      PIN_NUMBER='(2)';
      PIN_TYPE='UNSPEC';
      PINUSE='UNSPEC';
  end_pin;
  body
      PART_NAME='Q_RES';
      PHYS_DES_PREFIX='R';
      STANDARD='End of Design';
      LIFECYCLE='Comp-Approve';
      JEDEC_TYPE='R0402';
      ALT_SYMBOLS='(R0402-0201)';
      VALUE='150K';
      TOL='1%';
      WATTAGE='1/16W';
      CLASS='DISCRETE';
      DESCRIPTION='RES CHIP 150K 1/16W +-1%(0402)EF';
      COMPONENT_TYPE='CHIPR0402';
      LEAD_LENGTH='';
      DFM_EXCLUSION='';
      DAY='20180221';
      PARENT_PART_TYPE='Q_RES';
      PARENT_PPT='Q_RES';
      PARENT_PPT_PART='Q_RES_0402LF-150K,1%,1/16W,CHIP,CS41502FB04';
  end_body;
end_primitive;
primitive 'Q_RES_0402LF-150K,1%,1/16W,EMPA';
  pin
    'A':
      PIN_GROUP='1';
      PIN_NUMBER='(1)';
      PIN_TYPE='UNSPEC';
      PINUSE='UNSPEC';
    'B':
      PIN_GROUP='1';
      PIN_NUMBER='(2)';
      PIN_TYPE='UNSPEC';
      PINUSE='UNSPEC';
  end_pin;
  body
      PART_NAME='Q_RES';
      PHYS_DES_PREFIX='R';
      STANDARD='End of Design';
      LIFECYCLE='Comp-Approve';
      JEDEC_TYPE='R0402';
      ALT_SYMBOLS='(R0402-0201)';
      VALUE='150K';
      TOL='1%';
      WATTAGE='1/16W';
      CLASS='IO';
      DESCRIPTION='RES CHIP 150K 1/16W +-1%(0402)EF';
      COMPONENT_TYPE='CHIPR0402';
      LEAD_LENGTH='';
      DFM_EXCLUSION='';
      DAY='20180221';
      PARENT_PART_TYPE='Q_RES';
      PARENT_PPT='Q_RES';
      PARENT_PPT_PART='Q_RES_0402LF-150K,1%,1/16W,EMPTY,CS41502FB04';
  end_body;
end_primitive;
primitive 'Q_RES_0402LF-15K,1%,1/16W,CHIPA';
  pin
    'A':
      PIN_GROUP='1';
      PIN_NUMBER='(1)';
      PIN_TYPE='UNSPEC';
      PINUSE='UNSPEC';
    'B':
      PIN_GROUP='1';
      PIN_NUMBER='(2)';
      PIN_TYPE='UNSPEC';
      PINUSE='UNSPEC';
  end_pin;
  body
      PART_NAME='Q_RES';
      PHYS_DES_PREFIX='R';
      STANDARD='End of Design';
      LIFECYCLE='Comp-Approve';
      JEDEC_TYPE='R0402';
      ALT_SYMBOLS='(R0402-0201)';
      VALUE='15K';
      TOL='1%';
      WATTAGE='1/16W';
      CLASS='DISCRETE';
      DESCRIPTION='RES CHIP 15K 1/16W +-1%(0402)EF';
      COMPONENT_TYPE='CHIPR0402';
      LEAD_LENGTH='';
      DFM_EXCLUSION='';
      DAY='20191227';
      PARENT_PART_TYPE='Q_RES';
      PARENT_PPT='Q_RES';
      PARENT_PPT_PART='Q_RES_0402LF-15K,1%,1/16W,CHIP,CS31502FB05';
  end_body;
end_primitive;
primitive 'Q_RES_0402LF-16.9K,1%,1/16W,CHA';
  pin
    'A':
      PIN_GROUP='1';
      PIN_NUMBER='(1)';
      PIN_TYPE='UNSPEC';
      PINUSE='UNSPEC';
    'B':
      PIN_GROUP='1';
      PIN_NUMBER='(2)';
      PIN_TYPE='UNSPEC';
      PINUSE='UNSPEC';
  end_pin;
  body
      PART_NAME='Q_RES';
      PHYS_DES_PREFIX='R';
      STANDARD='End of Design';
      LIFECYCLE='Comp-Approve';
      JEDEC_TYPE='R0402';
      ALT_SYMBOLS='(R0402-0201)';
      VALUE='16.9K';
      TOL='1%';
      WATTAGE='1/16W';
      CLASS='DISCRETE';
      DESCRIPTION='RES CHIP 16.9K 1/16W +-1%(0402)EF';
      COMPONENT_TYPE='CHIPR0402';
      LEAD_LENGTH='';
      DFM_EXCLUSION='';
      DAY='20200615';
      PARENT_PART_TYPE='Q_RES';
      PARENT_PPT='Q_RES';
      PARENT_PPT_PART='Q_RES_0402LF-16.9K,1%,1/16W,CHIP,CS31692FB03';
  end_body;
end_primitive;
primitive 'Q_RES_0402LF-1K,1%,1/16W,CHIP,A';
  pin
    'A':
      PIN_GROUP='1';
      PIN_NUMBER='(1)';
      PIN_TYPE='UNSPEC';
      PINUSE='UNSPEC';
    'B':
      PIN_GROUP='1';
      PIN_NUMBER='(2)';
      PIN_TYPE='UNSPEC';
      PINUSE='UNSPEC';
  end_pin;
  body
      PART_NAME='Q_RES';
      PHYS_DES_PREFIX='R';
      STANDARD='End of Design';
      LIFECYCLE='Comp-Approve';
      JEDEC_TYPE='R0402';
      ALT_SYMBOLS='(R0402-0201)';
      VALUE='1K';
      TOL='1%';
      WATTAGE='1/16W';
      CLASS='DISCRETE';
      DESCRIPTION='RES CHIP 1K 1/16W +-1%(0402)EF';
      COMPONENT_TYPE='CHIPR0402';
      LEAD_LENGTH='';
      DFM_EXCLUSION='';
      DAY='20180208';
      PARENT_PART_TYPE='Q_RES';
      PARENT_PPT='Q_RES';
      PARENT_PPT_PART='Q_RES_0402LF-1K,1%,1/16W,CHIP,CS21002FB06';
  end_body;
end_primitive;
primitive 'Q_RES_0402LF-1K,1%,1/16W,EMPTYA';
  pin
    'A':
      PIN_GROUP='1';
      PIN_NUMBER='(1)';
      PIN_TYPE='UNSPEC';
      PINUSE='UNSPEC';
    'B':
      PIN_GROUP='1';
      PIN_NUMBER='(2)';
      PIN_TYPE='UNSPEC';
      PINUSE='UNSPEC';
  end_pin;
  body
      PART_NAME='Q_RES';
      PHYS_DES_PREFIX='R';
      STANDARD='End of Design';
      LIFECYCLE='Comp-Approve';
      JEDEC_TYPE='R0402';
      ALT_SYMBOLS='(R0402-0201)';
      VALUE='1K';
      TOL='1%';
      WATTAGE='1/16W';
      CLASS='IO';
      DESCRIPTION='RES CHIP 1K 1/16W +-1%(0402)EF';
      COMPONENT_TYPE='CHIPR0402';
      LEAD_LENGTH='';
      DFM_EXCLUSION='';
      DAY='20180208';
      PARENT_PART_TYPE='Q_RES';
      PARENT_PPT='Q_RES';
      PARENT_PPT_PART='Q_RES_0402LF-1K,1%,1/16W,EMPTY,CS21002FB06';
  end_body;
end_primitive;
primitive 'Q_RES_0402LF-1K,1%,1/16W,EMPTYB';
  pin
    'A':
      PIN_GROUP='1';
      PIN_NUMBER='(1)';
      PIN_TYPE='UNSPEC';
      PINUSE='UNSPEC';
    'B':
      PIN_GROUP='1';
      PIN_NUMBER='(2)';
      PIN_TYPE='UNSPEC';
      PINUSE='UNSPEC';
  end_pin;
  body
      PART_NAME='Q_RES';
      PHYS_DES_PREFIX='R';
      STANDARD='End of Design';
      LIFECYCLE='Comp-Approve';
      JEDEC_TYPE='R0402';
      ALT_SYMBOLS='(R0402-0201)';
      VALUE='1K';
      TOL='1%';
      WATTAGE='1/16W';
      CLASS='IO';
      DESCRIPTION='RES CHIP 1K 1/16W +-1% (0402)';
      COMPONENT_TYPE='CHIP0402';
      LEAD_LENGTH='';
      DFM_EXCLUSION='';
      DAY='';
      PARENT_PART_TYPE='Q_RES';
      PARENT_PPT='Q_RES';
      PARENT_PPT_PART='Q_RES_0402LF-1K,1%,1/16W,EMPTY,TMP_QCS21002FB24';
  end_body;
end_primitive;
primitive 'Q_RES_0402LF-2.2,1%,1/16W,CHIPA';
  pin
    'A':
      PIN_GROUP='1';
      PIN_NUMBER='(1)';
      PIN_TYPE='UNSPEC';
      PINUSE='UNSPEC';
    'B':
      PIN_GROUP='1';
      PIN_NUMBER='(2)';
      PIN_TYPE='UNSPEC';
      PINUSE='UNSPEC';
  end_pin;
  body
      PART_NAME='Q_RES';
      PHYS_DES_PREFIX='R';
      STANDARD='End of Design';
      LIFECYCLE='Comp-Approve';
      JEDEC_TYPE='R0402';
      ALT_SYMBOLS='(R0402-0201)';
      VALUE='2.2';
      TOL='1%';
      WATTAGE='1/16W';
      CLASS='DISCRETE';
      DESCRIPTION='RES CHIP 2.2 1/16W +-1%(0402)EF';
      COMPONENT_TYPE='CHIP0402';
      LEAD_LENGTH='';
      DFM_EXCLUSION='';
      DAY='20180212';
      PARENT_PART_TYPE='Q_RES';
      PARENT_PPT='Q_RES';
      PARENT_PPT_PART='Q_RES_0402LF-2.2,1%,1/16W,CHIP,CS-2202FB01';
  end_body;
end_primitive;
primitive 'Q_RES_0402LF-2.21K,1%,1/16W,EMA';
  pin
    'A':
      PIN_GROUP='1';
      PIN_NUMBER='(1)';
      PIN_TYPE='UNSPEC';
      PINUSE='UNSPEC';
    'B':
      PIN_GROUP='1';
      PIN_NUMBER='(2)';
      PIN_TYPE='UNSPEC';
      PINUSE='UNSPEC';
  end_pin;
  body
      PART_NAME='Q_RES';
      PHYS_DES_PREFIX='R';
      STANDARD='End of Design';
      LIFECYCLE='Comp-Approve';
      JEDEC_TYPE='R0402';
      ALT_SYMBOLS='(R0402-0201)';
      VALUE='2.21K';
      TOL='1%';
      WATTAGE='1/16W';
      CLASS='IO';
      DESCRIPTION='RES CHIP 2.21K 1/16W +-1%(0402)EF';
      COMPONENT_TYPE='CHIPR0402';
      LEAD_LENGTH='';
      DFM_EXCLUSION='';
      DAY='20180221';
      PARENT_PART_TYPE='Q_RES';
      PARENT_PPT='Q_RES';
      PARENT_PPT_PART='Q_RES_0402LF-2.21K,1%,1/16W,EMPTY,CS22212FB06';
  end_body;
end_primitive;
primitive 'Q_RES_0402LF-2.2K,5%,1/16W,CHIA';
  pin
    'A':
      PIN_GROUP='1';
      PIN_NUMBER='(1)';
      PIN_TYPE='UNSPEC';
      PINUSE='UNSPEC';
    'B':
      PIN_GROUP='1';
      PIN_NUMBER='(2)';
      PIN_TYPE='UNSPEC';
      PINUSE='UNSPEC';
  end_pin;
  body
      PART_NAME='Q_RES';
      PHYS_DES_PREFIX='R';
      STANDARD='End of Design';
      LIFECYCLE='Comp-Approve';
      JEDEC_TYPE='R0402';
      ALT_SYMBOLS='(R0402-0201)';
      VALUE='2.2K';
      TOL='5%';
      WATTAGE='1/16W';
      CLASS='DISCRETE';
      DESCRIPTION='RES CHIP 2.2K 1/16W +-5%(0402)EF';
      COMPONENT_TYPE='CHIP0402';
      LEAD_LENGTH='';
      DFM_EXCLUSION='';
      DAY='20180212';
      PARENT_PART_TYPE='Q_RES';
      PARENT_PPT='Q_RES';
      PARENT_PPT_PART='Q_RES_0402LF-2.2K,5%,1/16W,CHIP,CS22202JB07';
  end_body;
end_primitive;
primitive 'Q_RES_0402LF-2.74K,1%,1/16W,CHA';
  pin
    'A':
      PIN_GROUP='1';
      PIN_NUMBER='(1)';
      PIN_TYPE='UNSPEC';
      PINUSE='UNSPEC';
    'B':
      PIN_GROUP='1';
      PIN_NUMBER='(2)';
      PIN_TYPE='UNSPEC';
      PINUSE='UNSPEC';
  end_pin;
  body
      PART_NAME='Q_RES';
      PHYS_DES_PREFIX='R';
      STANDARD='End of Design';
      LIFECYCLE='Comp-Approve';
      JEDEC_TYPE='R0402';
      ALT_SYMBOLS='(R0402-0201)';
      VALUE='2.74K';
      TOL='1%';
      WATTAGE='1/16W';
      CLASS='DISCRETE';
      DESCRIPTION='RES CHIP 2.74K 1/16W +-1%(0402)EF';
      COMPONENT_TYPE='CHIPR0402';
      LEAD_LENGTH='';
      DFM_EXCLUSION='';
      DAY='20210804';
      PARENT_PART_TYPE='Q_RES';
      PARENT_PPT='Q_RES';
      PARENT_PPT_PART='Q_RES_0402LF-2.74K,1%,1/16W,CHIP,CS22742FB05';
  end_body;
end_primitive;
primitive 'Q_RES_0402LF-2.87K,1%,1/16W,CHA';
  pin
    'A':
      PIN_GROUP='1';
      PIN_NUMBER='(1)';
      PIN_TYPE='UNSPEC';
      PINUSE='UNSPEC';
    'B':
      PIN_GROUP='1';
      PIN_NUMBER='(2)';
      PIN_TYPE='UNSPEC';
      PINUSE='UNSPEC';
  end_pin;
  body
      PART_NAME='Q_RES';
      PHYS_DES_PREFIX='R';
      STANDARD='End of Design';
      LIFECYCLE='Comp-Approve';
      JEDEC_TYPE='R0402';
      ALT_SYMBOLS='(R0402-0201)';
      VALUE='2.87K';
      TOL='1%';
      WATTAGE='1/16W';
      CLASS='DISCRETE';
      DESCRIPTION='RES CHIP 2.87K 1/16W +-1%(0402)EF';
      COMPONENT_TYPE='CHIPR0402';
      LEAD_LENGTH='';
      DFM_EXCLUSION='';
      DAY='20180221';
      PARENT_PART_TYPE='Q_RES';
      PARENT_PPT='Q_RES';
      PARENT_PPT_PART='Q_RES_0402LF-2.87K,1%,1/16W,CHIP,CS22872FB03';
  end_body;
end_primitive;
primitive 'Q_RES_0402LF-20.5K,1%,1/16W,CHA';
  pin
    'A':
      PIN_GROUP='1';
      PIN_NUMBER='(1)';
      PIN_TYPE='UNSPEC';
      PINUSE='UNSPEC';
    'B':
      PIN_GROUP='1';
      PIN_NUMBER='(2)';
      PIN_TYPE='UNSPEC';
      PINUSE='UNSPEC';
  end_pin;
  body
      PART_NAME='Q_RES';
      PHYS_DES_PREFIX='R';
      STANDARD='End of Design';
      LIFECYCLE='Comp-Approve';
      JEDEC_TYPE='R0402';
      ALT_SYMBOLS='(R0402-0201)';
      VALUE='20.5K';
      TOL='1%';
      WATTAGE='1/16W';
      CLASS='DISCRETE';
      DESCRIPTION='RES CHIP 20.5K 1/16W +-1%(0402)EF';
      COMPONENT_TYPE='CHIPR0402';
      LEAD_LENGTH='';
      DFM_EXCLUSION='';
      DAY='20200602';
      PARENT_PART_TYPE='Q_RES';
      PARENT_PPT='Q_RES';
      PARENT_PPT_PART='Q_RES_0402LF-20.5K,1%,1/16W,CHIP,CS32052FB02';
  end_body;
end_primitive;
primitive 'Q_RES_0402LF-200,1%,1/16W,CHIPA';
  pin
    'A':
      PIN_GROUP='1';
      PIN_NUMBER='(1)';
      PIN_TYPE='UNSPEC';
      PINUSE='UNSPEC';
    'B':
      PIN_GROUP='1';
      PIN_NUMBER='(2)';
      PIN_TYPE='UNSPEC';
      PINUSE='UNSPEC';
  end_pin;
  body
      PART_NAME='Q_RES';
      PHYS_DES_PREFIX='R';
      STANDARD='End of Design';
      LIFECYCLE='Comp-Approve';
      JEDEC_TYPE='R0402';
      ALT_SYMBOLS='(R0402-0201)';
      VALUE='200';
      TOL='1%';
      WATTAGE='1/16W';
      CLASS='DISCRETE';
      DESCRIPTION='RES CHIP 200 1/16W +-1%(0402)EF';
      COMPONENT_TYPE='CHIPR0402';
      LEAD_LENGTH='';
      DFM_EXCLUSION='';
      DAY='20180208';
      PARENT_PART_TYPE='Q_RES';
      PARENT_PPT='Q_RES';
      PARENT_PPT_PART='Q_RES_0402LF-200,1%,1/16W,CHIP,CS12002FB06';
  end_body;
end_primitive;
primitive 'Q_RES_0402LF-200K,1%,1/16W,CHIA';
  pin
    'A':
      PIN_GROUP='1';
      PIN_NUMBER='(1)';
      PIN_TYPE='UNSPEC';
      PINUSE='UNSPEC';
    'B':
      PIN_GROUP='1';
      PIN_NUMBER='(2)';
      PIN_TYPE='UNSPEC';
      PINUSE='UNSPEC';
  end_pin;
  body
      PART_NAME='Q_RES';
      PHYS_DES_PREFIX='R';
      STANDARD='End of Design';
      LIFECYCLE='Comp-Approve';
      JEDEC_TYPE='R0402';
      ALT_SYMBOLS='(R0402-0201)';
      VALUE='200K';
      TOL='1%';
      WATTAGE='1/16W';
      CLASS='DISCRETE';
      DESCRIPTION='RES CHIP 200K 1/16W +-1%(0402)EF';
      COMPONENT_TYPE='CHIPR0402';
      LEAD_LENGTH='';
      DFM_EXCLUSION='';
      DAY='20180208';
      PARENT_PART_TYPE='Q_RES';
      PARENT_PPT='Q_RES';
      PARENT_PPT_PART='Q_RES_0402LF-200K,1%,1/16W,CHIP,CS42002FB05';
  end_body;
end_primitive;
primitive 'Q_RES_0402LF-20K,1%,1/16W,CHIPA';
  pin
    'A':
      PIN_GROUP='1';
      PIN_NUMBER='(1)';
      PIN_TYPE='UNSPEC';
      PINUSE='UNSPEC';
    'B':
      PIN_GROUP='1';
      PIN_NUMBER='(2)';
      PIN_TYPE='UNSPEC';
      PINUSE='UNSPEC';
  end_pin;
  body
      PART_NAME='Q_RES';
      PHYS_DES_PREFIX='R';
      STANDARD='End of Design';
      LIFECYCLE='Comp-Approve';
      JEDEC_TYPE='R0402';
      ALT_SYMBOLS='(R0402-0201)';
      VALUE='20K';
      TOL='1%';
      WATTAGE='1/16W';
      CLASS='DISCRETE';
      DESCRIPTION='RES CHIP 20K 1/16W +-1%(0402)EF';
      COMPONENT_TYPE='CHIPR0402';
      LEAD_LENGTH='';
      DFM_EXCLUSION='';
      DAY='20180208';
      PARENT_PART_TYPE='Q_RES';
      PARENT_PPT='Q_RES';
      PARENT_PPT_PART='Q_RES_0402LF-20K,1%,1/16W,CHIP,CS32002FB06';
  end_body;
end_primitive;
primitive 'Q_RES_0402LF-22,1%,1/16W,CHIP,A';
  pin
    'A':
      PIN_GROUP='1';
      PIN_NUMBER='(1)';
      PIN_TYPE='UNSPEC';
      PINUSE='UNSPEC';
    'B':
      PIN_GROUP='1';
      PIN_NUMBER='(2)';
      PIN_TYPE='UNSPEC';
      PINUSE='UNSPEC';
  end_pin;
  body
      PART_NAME='Q_RES';
      PHYS_DES_PREFIX='R';
      STANDARD='End of Design';
      LIFECYCLE='Comp-Approve';
      JEDEC_TYPE='R0402';
      ALT_SYMBOLS='(R0402-0201)';
      VALUE='22';
      TOL='1%';
      WATTAGE='1/16W';
      CLASS='DISCRETE';
      DESCRIPTION='RES CHIP 22 1/16W +-1%(0402)EF';
      COMPONENT_TYPE='CHIP0402';
      LEAD_LENGTH='';
      DFM_EXCLUSION='';
      DAY='20180212';
      PARENT_PART_TYPE='Q_RES';
      PARENT_PPT='Q_RES';
      PARENT_PPT_PART='Q_RES_0402LF-22,1%,1/16W,CHIP,CS02202FB02';
  end_body;
end_primitive;
primitive 'Q_RES_0402LF-220,1%,1/16W,CHIPA';
  pin
    'A':
      PIN_GROUP='1';
      PIN_NUMBER='(1)';
      PIN_TYPE='UNSPEC';
      PINUSE='UNSPEC';
    'B':
      PIN_GROUP='1';
      PIN_NUMBER='(2)';
      PIN_TYPE='UNSPEC';
      PINUSE='UNSPEC';
  end_pin;
  body
      PART_NAME='Q_RES';
      PHYS_DES_PREFIX='R';
      STANDARD='';
      LIFECYCLE='';
      JEDEC_TYPE='R0402';
      ALT_SYMBOLS='(R0402-0201)';
      VALUE='220';
      TOL='1%';
      WATTAGE='1/16W';
      CLASS='DISCRETE';
      DESCRIPTION='RES CHIP 220 1/16W +-1%(0402)EF';
      COMPONENT_TYPE='CHIP0402';
      LEAD_LENGTH='';
      DFM_EXCLUSION='';
      DAY='20180212';
      PARENT_PART_TYPE='Q_RES';
      PARENT_PPT='Q_RES';
      PARENT_PPT_PART='Q_RES_0402LF-220,1%,1/16W,CHIP,CS12202FB04';
  end_body;
end_primitive;
primitive 'Q_RES_0402LF-240,1%,1/16W,CHIPA';
  pin
    'A':
      PIN_GROUP='1';
      PIN_NUMBER='(1)';
      PIN_TYPE='UNSPEC';
      PINUSE='UNSPEC';
    'B':
      PIN_GROUP='1';
      PIN_NUMBER='(2)';
      PIN_TYPE='UNSPEC';
      PINUSE='UNSPEC';
  end_pin;
  body
      PART_NAME='Q_RES';
      PHYS_DES_PREFIX='R';
      STANDARD='End of Design';
      LIFECYCLE='Comp-Approve';
      JEDEC_TYPE='R0402';
      ALT_SYMBOLS='(R0402-0201)';
      VALUE='240';
      TOL='1%';
      WATTAGE='1/16W';
      CLASS='DISCRETE';
      DESCRIPTION='RES CHIP 240 1/16W +-1%(0402)EF';
      COMPONENT_TYPE='CHIPR0402';
      LEAD_LENGTH='';
      DFM_EXCLUSION='';
      DAY='20180221';
      PARENT_PART_TYPE='Q_RES';
      PARENT_PPT='Q_RES';
      PARENT_PPT_PART='Q_RES_0402LF-240,1%,1/16W,CHIP,CS12402FB01';
  end_body;
end_primitive;
primitive 'Q_RES_0402LF-25.5K,1%,1/16W,CHA';
  pin
    'A':
      PIN_GROUP='1';
      PIN_NUMBER='(1)';
      PIN_TYPE='UNSPEC';
      PINUSE='UNSPEC';
    'B':
      PIN_GROUP='1';
      PIN_NUMBER='(2)';
      PIN_TYPE='UNSPEC';
      PINUSE='UNSPEC';
  end_pin;
  body
      PART_NAME='Q_RES';
      PHYS_DES_PREFIX='R';
      STANDARD='End of Design';
      LIFECYCLE='Comp-Approve';
      JEDEC_TYPE='R0402';
      ALT_SYMBOLS='(R0402-0201)';
      VALUE='25.5K';
      TOL='1%';
      WATTAGE='1/16W';
      CLASS='DISCRETE';
      DESCRIPTION='RES CHIP 25.5K 1/16W +-1%(0402)EF';
      COMPONENT_TYPE='CHIPR0402';
      LEAD_LENGTH='';
      DFM_EXCLUSION='';
      DAY='20180221';
      PARENT_PART_TYPE='Q_RES';
      PARENT_PPT='Q_RES';
      PARENT_PPT_PART='Q_RES_0402LF-25.5K,1%,1/16W,CHIP,CS32552FB06';
  end_body;
end_primitive;
primitive 'Q_RES_0402LF-2K,1%,1/16W,CHIP,A';
  pin
    'A':
      PIN_GROUP='1';
      PIN_NUMBER='(1)';
      PIN_TYPE='UNSPEC';
      PINUSE='UNSPEC';
    'B':
      PIN_GROUP='1';
      PIN_NUMBER='(2)';
      PIN_TYPE='UNSPEC';
      PINUSE='UNSPEC';
  end_pin;
  body
      PART_NAME='Q_RES';
      PHYS_DES_PREFIX='R';
      STANDARD='End of Design';
      LIFECYCLE='Comp-Approve';
      JEDEC_TYPE='R0402';
      ALT_SYMBOLS='(R0402-0201)';
      VALUE='2K';
      TOL='1%';
      WATTAGE='1/16W';
      CLASS='DISCRETE';
      DESCRIPTION='RES CHIP 2K 1/16W +-1%(0402)EF';
      COMPONENT_TYPE='CHIPR0402';
      LEAD_LENGTH='';
      DFM_EXCLUSION='';
      DAY='20180221';
      PARENT_PART_TYPE='Q_RES';
      PARENT_PPT='Q_RES';
      PARENT_PPT_PART='Q_RES_0402LF-2K,1%,1/16W,CHIP,CS22002FB07';
  end_body;
end_primitive;
primitive 'Q_RES_0402LF-2K,1%,1/16W,EMPTYA';
  pin
    'A':
      PIN_GROUP='1';
      PIN_NUMBER='(1)';
      PIN_TYPE='UNSPEC';
      PINUSE='UNSPEC';
    'B':
      PIN_GROUP='1';
      PIN_NUMBER='(2)';
      PIN_TYPE='UNSPEC';
      PINUSE='UNSPEC';
  end_pin;
  body
      PART_NAME='Q_RES';
      PHYS_DES_PREFIX='R';
      STANDARD='End of Design';
      LIFECYCLE='Comp-Approve';
      JEDEC_TYPE='R0402';
      ALT_SYMBOLS='(R0402-0201)';
      VALUE='2K';
      TOL='1%';
      WATTAGE='1/16W';
      CLASS='IO';
      DESCRIPTION='RES CHIP 2K 1/16W +-1%(0402)EF';
      COMPONENT_TYPE='CHIPR0402';
      LEAD_LENGTH='';
      DFM_EXCLUSION='';
      DAY='20180221';
      PARENT_PART_TYPE='Q_RES';
      PARENT_PPT='Q_RES';
      PARENT_PPT_PART='Q_RES_0402LF-2K,1%,1/16W,EMPTY,CS22002FB07';
  end_body;
end_primitive;
primitive 'Q_RES_0402LF-316,1%,1/16W,CHIPA';
  pin
    'A':
      PIN_GROUP='1';
      PIN_NUMBER='(1)';
      PIN_TYPE='UNSPEC';
      PINUSE='UNSPEC';
    'B':
      PIN_GROUP='1';
      PIN_NUMBER='(2)';
      PIN_TYPE='UNSPEC';
      PINUSE='UNSPEC';
  end_pin;
  body
      PART_NAME='Q_RES';
      PHYS_DES_PREFIX='R';
      STANDARD='';
      LIFECYCLE='';
      JEDEC_TYPE='R0402';
      ALT_SYMBOLS='(R0402-0201)';
      VALUE='316';
      TOL='1%';
      WATTAGE='1/16W';
      CLASS='DISCRETE';
      DESCRIPTION='RES CHIP 316 1/16W +-1%(0402)EF';
      COMPONENT_TYPE='CHIPR0402';
      LEAD_LENGTH='';
      DFM_EXCLUSION='';
      DAY='20210727';
      PARENT_PART_TYPE='Q_RES';
      PARENT_PPT='Q_RES';
      PARENT_PPT_PART='Q_RES_0402LF-316,1%,1/16W,CHIP,CS13162FB01';
  end_body;
end_primitive;
primitive 'Q_RES_0402LF-33.2,1%,1/16W,CHIA';
  pin
    'A':
      PIN_GROUP='1';
      PIN_NUMBER='(1)';
      PIN_TYPE='UNSPEC';
      PINUSE='UNSPEC';
    'B':
      PIN_GROUP='1';
      PIN_NUMBER='(2)';
      PIN_TYPE='UNSPEC';
      PINUSE='UNSPEC';
  end_pin;
  body
      PART_NAME='Q_RES';
      PHYS_DES_PREFIX='R';
      STANDARD='End of Design';
      LIFECYCLE='Comp-Approve';
      JEDEC_TYPE='R0402';
      ALT_SYMBOLS='(R0402-0201)';
      VALUE='33.2';
      TOL='1%';
      WATTAGE='1/16W';
      CLASS='DISCRETE';
      DESCRIPTION='RES CHIP 33.2 1/16W +-1%(0402)EF';
      COMPONENT_TYPE='CHIPR0402';
      LEAD_LENGTH='';
      DFM_EXCLUSION='';
      DAY='20180208';
      PARENT_PART_TYPE='Q_RES';
      PARENT_PPT='Q_RES';
      PARENT_PPT_PART='Q_RES_0402LF-33.2,1%,1/16W,CHIP,CS03322FB03';
  end_body;
end_primitive;
primitive 'Q_RES_0402LF-33.2,1%,1/16W,EMPA';
  pin
    'A':
      PIN_GROUP='1';
      PIN_NUMBER='(1)';
      PIN_TYPE='UNSPEC';
      PINUSE='UNSPEC';
    'B':
      PIN_GROUP='1';
      PIN_NUMBER='(2)';
      PIN_TYPE='UNSPEC';
      PINUSE='UNSPEC';
  end_pin;
  body
      PART_NAME='Q_RES';
      PHYS_DES_PREFIX='R';
      STANDARD='End of Design';
      LIFECYCLE='Comp-Approve';
      JEDEC_TYPE='R0402';
      ALT_SYMBOLS='(R0402-0201)';
      VALUE='33.2';
      TOL='1%';
      WATTAGE='1/16W';
      CLASS='IO';
      DESCRIPTION='RES CHIP 33.2 1/16W +-1%(0402)EF';
      COMPONENT_TYPE='CHIPR0402';
      LEAD_LENGTH='';
      DFM_EXCLUSION='';
      DAY='20180208';
      PARENT_PART_TYPE='Q_RES';
      PARENT_PPT='Q_RES';
      PARENT_PPT_PART='Q_RES_0402LF-33.2,1%,1/16W,EMPTY,CS03322FB03';
  end_body;
end_primitive;
primitive 'Q_RES_0402LF-330,1%,1/16W,CHIPA';
  pin
    'A':
      PIN_GROUP='1';
      PIN_NUMBER='(1)';
      PIN_TYPE='UNSPEC';
      PINUSE='UNSPEC';
    'B':
      PIN_GROUP='1';
      PIN_NUMBER='(2)';
      PIN_TYPE='UNSPEC';
      PINUSE='UNSPEC';
  end_pin;
  body
      PART_NAME='Q_RES';
      PHYS_DES_PREFIX='R';
      STANDARD='End of Design';
      LIFECYCLE='Comp-Approve';
      JEDEC_TYPE='R0402';
      ALT_SYMBOLS='(R0402-0201)';
      VALUE='330';
      TOL='1%';
      WATTAGE='1/16W';
      CLASS='DISCRETE';
      DESCRIPTION='RES CHIP 330 1/16W +-1%(0402)EF';
      COMPONENT_TYPE='CHIP0402';
      LEAD_LENGTH='';
      DFM_EXCLUSION='';
      DAY='20180212';
      PARENT_PART_TYPE='Q_RES';
      PARENT_PPT='Q_RES';
      PARENT_PPT_PART='Q_RES_0402LF-330,1%,1/16W,CHIP,CS13302FB00';
  end_body;
end_primitive;
primitive 'Q_RES_0402LF-4.7K,1%,1/16W,CHIA';
  pin
    'A':
      PIN_GROUP='1';
      PIN_NUMBER='(1)';
      PIN_TYPE='UNSPEC';
      PINUSE='UNSPEC';
    'B':
      PIN_GROUP='1';
      PIN_NUMBER='(2)';
      PIN_TYPE='UNSPEC';
      PINUSE='UNSPEC';
  end_pin;
  body
      PART_NAME='Q_RES';
      PHYS_DES_PREFIX='R';
      STANDARD='End of Design';
      LIFECYCLE='Comp-Approve';
      JEDEC_TYPE='R0402';
      ALT_SYMBOLS='(R0402-0201)';
      VALUE='4.7K';
      TOL='1%';
      WATTAGE='1/16W';
      CLASS='DISCRETE';
      DESCRIPTION='RES CHIP 4.7K 1/16W +-1%(0402)EF';
      COMPONENT_TYPE='CHIPR0402';
      LEAD_LENGTH='';
      DFM_EXCLUSION='';
      DAY='20180208';
      PARENT_PART_TYPE='Q_RES';
      PARENT_PPT='Q_RES';
      PARENT_PPT_PART='Q_RES_0402LF-4.7K,1%,1/16W,CHIP,CS24702FB06';
  end_body;
end_primitive;
primitive 'Q_RES_0402LF-4.7K,1%,1/16W,EMPA';
  pin
    'A':
      PIN_GROUP='1';
      PIN_NUMBER='(1)';
      PIN_TYPE='UNSPEC';
      PINUSE='UNSPEC';
    'B':
      PIN_GROUP='1';
      PIN_NUMBER='(2)';
      PIN_TYPE='UNSPEC';
      PINUSE='UNSPEC';
  end_pin;
  body
      PART_NAME='Q_RES';
      PHYS_DES_PREFIX='R';
      STANDARD='End of Design';
      LIFECYCLE='Comp-Approve';
      JEDEC_TYPE='R0402';
      ALT_SYMBOLS='(R0402-0201)';
      VALUE='4.7K';
      TOL='1%';
      WATTAGE='1/16W';
      CLASS='IO';
      DESCRIPTION='RES CHIP 4.7K 1/16W +-1%(0402)EF';
      COMPONENT_TYPE='CHIPR0402';
      LEAD_LENGTH='';
      DFM_EXCLUSION='';
      DAY='20180208';
      PARENT_PART_TYPE='Q_RES';
      PARENT_PPT='Q_RES';
      PARENT_PPT_PART='Q_RES_0402LF-4.7K,1%,1/16W,EMPTY,CS24702FB06';
  end_body;
end_primitive;
primitive 'Q_RES_0402LF-4.7K,1%,1/16W,EMPB';
  pin
    'A':
      PIN_GROUP='1';
      PIN_NUMBER='(1)';
      PIN_TYPE='UNSPEC';
      PINUSE='UNSPEC';
    'B':
      PIN_GROUP='1';
      PIN_NUMBER='(2)';
      PIN_TYPE='UNSPEC';
      PINUSE='UNSPEC';
  end_pin;
  body
      PART_NAME='Q_RES';
      PHYS_DES_PREFIX='R';
      STANDARD='End of Design';
      LIFECYCLE='Comp-Approve';
      JEDEC_TYPE='R0402';
      ALT_SYMBOLS='(R0402-0201)';
      VALUE='4.7K';
      TOL='1%';
      WATTAGE='1/16W';
      CLASS='IO';
      DESCRIPTION='RES CHIP 4.7K 1/16W +-1%(0402)';
      COMPONENT_TYPE='CHIP0402';
      LEAD_LENGTH='';
      DFM_EXCLUSION='';
      DAY='20100708';
      PARENT_PART_TYPE='Q_RES';
      PARENT_PPT='Q_RES';
      PARENT_PPT_PART='Q_RES_0402LF-4.7K,1%,1/16W,EMPTY,CS24702FB10';
  end_body;
end_primitive;
primitive 'Q_RES_0402LF-40.2,1%,1/16W,CHIA';
  pin
    'A':
      PIN_GROUP='1';
      PIN_NUMBER='(1)';
      PIN_TYPE='UNSPEC';
      PINUSE='UNSPEC';
    'B':
      PIN_GROUP='1';
      PIN_NUMBER='(2)';
      PIN_TYPE='UNSPEC';
      PINUSE='UNSPEC';
  end_pin;
  body
      PART_NAME='Q_RES';
      PHYS_DES_PREFIX='R';
      STANDARD='End of Design';
      LIFECYCLE='Comp-Approve';
      JEDEC_TYPE='R0402';
      ALT_SYMBOLS='(R0402-0201)';
      VALUE='40.2';
      TOL='1%';
      WATTAGE='1/16W';
      CLASS='DISCRETE';
      DESCRIPTION='RES CHIP 40.2 1/16W +-1%(0402)';
      COMPONENT_TYPE='CHIP0402';
      LEAD_LENGTH='';
      DFM_EXCLUSION='';
      DAY='20140630';
      PARENT_PART_TYPE='Q_RES';
      PARENT_PPT='Q_RES';
      PARENT_PPT_PART='Q_RES_0402LF-40.2,1%,1/16W,CHIP,CS04022FB28';
  end_body;
end_primitive;
primitive 'Q_RES_0402LF-402,1%,1/16W,CHIPA';
  pin
    'A':
      PIN_GROUP='1';
      PIN_NUMBER='(1)';
      PIN_TYPE='UNSPEC';
      PINUSE='UNSPEC';
    'B':
      PIN_GROUP='1';
      PIN_NUMBER='(2)';
      PIN_TYPE='UNSPEC';
      PINUSE='UNSPEC';
  end_pin;
  body
      PART_NAME='Q_RES';
      PHYS_DES_PREFIX='R';
      STANDARD='End of Design';
      LIFECYCLE='Comp-Approve';
      JEDEC_TYPE='R0402';
      ALT_SYMBOLS='(R0402-0201)';
      VALUE='402';
      TOL='1%';
      WATTAGE='1/16W';
      CLASS='DISCRETE';
      DESCRIPTION='RES CHIP 402 1/16W +-1%(0402)EF';
      COMPONENT_TYPE='CHIPR0402';
      LEAD_LENGTH='';
      DFM_EXCLUSION='';
      DAY='20180221';
      PARENT_PART_TYPE='Q_RES';
      PARENT_PPT='Q_RES';
      PARENT_PPT_PART='Q_RES_0402LF-402,1%,1/16W,CHIP,CS14022FB02';
  end_body;
end_primitive;
primitive 'Q_RES_0402LF-470K,1%,1/16W,CHIA';
  pin
    'A':
      PIN_GROUP='1';
      PIN_NUMBER='(1)';
      PIN_TYPE='UNSPEC';
      PINUSE='UNSPEC';
    'B':
      PIN_GROUP='1';
      PIN_NUMBER='(2)';
      PIN_TYPE='UNSPEC';
      PINUSE='UNSPEC';
  end_pin;
  body
      PART_NAME='Q_RES';
      PHYS_DES_PREFIX='R';
      STANDARD='End of Design';
      LIFECYCLE='Comp-Approve';
      JEDEC_TYPE='R0402';
      ALT_SYMBOLS='(R0402-0201)';
      VALUE='470K';
      TOL='1%';
      WATTAGE='1/16W';
      CLASS='DISCRETE';
      DESCRIPTION='RES CHIP 470K 1/16W +-1%(0402)EF';
      COMPONENT_TYPE='CHIPR0402';
      LEAD_LENGTH='';
      DFM_EXCLUSION='';
      DAY='20190906';
      PARENT_PART_TYPE='Q_RES';
      PARENT_PPT='Q_RES';
      PARENT_PPT_PART='Q_RES_0402LF-470K,1%,1/16W,CHIP,CS44702FB02';
  end_body;
end_primitive;
primitive 'Q_RES_0402LF-47K,1%,1/16W,CHIPA';
  pin
    'A':
      PIN_GROUP='1';
      PIN_NUMBER='(1)';
      PIN_TYPE='UNSPEC';
      PINUSE='UNSPEC';
    'B':
      PIN_GROUP='1';
      PIN_NUMBER='(2)';
      PIN_TYPE='UNSPEC';
      PINUSE='UNSPEC';
  end_pin;
  body
      PART_NAME='Q_RES';
      PHYS_DES_PREFIX='R';
      STANDARD='End of Design';
      LIFECYCLE='Comp-Approve';
      JEDEC_TYPE='R0402';
      ALT_SYMBOLS='(R0402-0201)';
      VALUE='47K';
      TOL='1%';
      WATTAGE='1/16W';
      CLASS='DISCRETE';
      DESCRIPTION='RES CHIP 47K 1/16W +-1%(0402)EF';
      COMPONENT_TYPE='CHIPR0402';
      LEAD_LENGTH='';
      DFM_EXCLUSION='';
      DAY='20180208';
      PARENT_PART_TYPE='Q_RES';
      PARENT_PPT='Q_RES';
      PARENT_PPT_PART='Q_RES_0402LF-47K,1%,1/16W,CHIP,CS34702FB01';
  end_body;
end_primitive;
primitive 'Q_RES_0402LF-49.9,1%,1/16W,CHIA';
  pin
    'A':
      PIN_GROUP='1';
      PIN_NUMBER='(1)';
      PIN_TYPE='UNSPEC';
      PINUSE='UNSPEC';
    'B':
      PIN_GROUP='1';
      PIN_NUMBER='(2)';
      PIN_TYPE='UNSPEC';
      PINUSE='UNSPEC';
  end_pin;
  body
      PART_NAME='Q_RES';
      PHYS_DES_PREFIX='R';
      STANDARD='End of Design';
      LIFECYCLE='Comp-Approve';
      JEDEC_TYPE='R0402';
      ALT_SYMBOLS='(R0402-0201)';
      VALUE='49.9';
      TOL='1%';
      WATTAGE='1/16W';
      CLASS='DISCRETE';
      DESCRIPTION='RES CHIP 49.9 1/16W +-1%(0402)EF';
      COMPONENT_TYPE='CHIPR0402';
      LEAD_LENGTH='';
      DFM_EXCLUSION='';
      DAY='20180208';
      PARENT_PART_TYPE='Q_RES';
      PARENT_PPT='Q_RES';
      PARENT_PPT_PART='Q_RES_0402LF-49.9,1%,1/16W,CHIP,CS04992FB07';
  end_body;
end_primitive;
primitive 'Q_RES_0402LF-49.9,1%,1/16W,EMPA';
  pin
    'A':
      PIN_GROUP='1';
      PIN_NUMBER='(1)';
      PIN_TYPE='UNSPEC';
      PINUSE='UNSPEC';
    'B':
      PIN_GROUP='1';
      PIN_NUMBER='(2)';
      PIN_TYPE='UNSPEC';
      PINUSE='UNSPEC';
  end_pin;
  body
      PART_NAME='Q_RES';
      PHYS_DES_PREFIX='R';
      STANDARD='End of Design';
      LIFECYCLE='Comp-Approve';
      JEDEC_TYPE='R0402';
      ALT_SYMBOLS='(R0402-0201)';
      VALUE='49.9';
      TOL='1%';
      WATTAGE='1/16W';
      CLASS='IO';
      DESCRIPTION='RES CHIP 49.9 1/16W +-1%(0402)EF';
      COMPONENT_TYPE='CHIPR0402';
      LEAD_LENGTH='';
      DFM_EXCLUSION='';
      DAY='20180208';
      PARENT_PART_TYPE='Q_RES';
      PARENT_PPT='Q_RES';
      PARENT_PPT_PART='Q_RES_0402LF-49.9,1%,1/16W,EMPTY,CS04992FB07';
  end_body;
end_primitive;
primitive 'Q_RES_0402LF-49.9K,1%,1/16W,CHA';
  pin
    'A':
      PIN_GROUP='1';
      PIN_NUMBER='(1)';
      PIN_TYPE='UNSPEC';
      PINUSE='UNSPEC';
    'B':
      PIN_GROUP='1';
      PIN_NUMBER='(2)';
      PIN_TYPE='UNSPEC';
      PINUSE='UNSPEC';
  end_pin;
  body
      PART_NAME='Q_RES';
      PHYS_DES_PREFIX='R';
      STANDARD='End of Design';
      LIFECYCLE='Comp-Approve';
      JEDEC_TYPE='R0402';
      ALT_SYMBOLS='(R0402-0201)';
      VALUE='49.9K';
      TOL='1%';
      WATTAGE='1/16W';
      CLASS='DISCRETE';
      DESCRIPTION='RES CHIP 49.9K 1/16W +-1%(0402)EF';
      COMPONENT_TYPE='CHIP0402';
      LEAD_LENGTH='';
      DFM_EXCLUSION='';
      DAY='20180212';
      PARENT_PART_TYPE='Q_RES';
      PARENT_PPT='Q_RES';
      PARENT_PPT_PART='Q_RES_0402LF-49.9K,1%,1/16W,CHIP,CS34992FB05';
  end_body;
end_primitive;
primitive 'Q_RES_0402LF-499,1%,1/16W,CHIPA';
  pin
    'A':
      PIN_GROUP='1';
      PIN_NUMBER='(1)';
      PIN_TYPE='UNSPEC';
      PINUSE='UNSPEC';
    'B':
      PIN_GROUP='1';
      PIN_NUMBER='(2)';
      PIN_TYPE='UNSPEC';
      PINUSE='UNSPEC';
  end_pin;
  body
      PART_NAME='Q_RES';
      PHYS_DES_PREFIX='R';
      STANDARD='End of Design';
      LIFECYCLE='Comp-Approve';
      JEDEC_TYPE='R0402';
      ALT_SYMBOLS='(R0402-0201)';
      VALUE='499';
      TOL='1%';
      WATTAGE='1/16W';
      CLASS='DISCRETE';
      DESCRIPTION='RES CHIP 499 1/16W +-1%(0402)EF';
      COMPONENT_TYPE='CHIPR0402';
      LEAD_LENGTH='';
      DFM_EXCLUSION='';
      DAY='20180221';
      PARENT_PART_TYPE='Q_RES';
      PARENT_PPT='Q_RES';
      PARENT_PPT_PART='Q_RES_0402LF-499,1%,1/16W,CHIP,CS14992FB06';
  end_body;
end_primitive;
primitive 'Q_RES_0402LF-5.1,5%,1/16W,CHIPA';
  pin
    'A':
      PIN_GROUP='1';
      PIN_NUMBER='(1)';
      PIN_TYPE='UNSPEC';
      PINUSE='UNSPEC';
    'B':
      PIN_GROUP='1';
      PIN_NUMBER='(2)';
      PIN_TYPE='UNSPEC';
      PINUSE='UNSPEC';
  end_pin;
  body
      PART_NAME='Q_RES';
      PHYS_DES_PREFIX='R';
      STANDARD='';
      LIFECYCLE='';
      JEDEC_TYPE='R0402';
      ALT_SYMBOLS='(R0402-0201)';
      VALUE='5.1';
      TOL='5%';
      WATTAGE='1/16W';
      CLASS='DISCRETE';
      DESCRIPTION='RES CHIP 5.1 1/16W +-5%(0402)EF';
      COMPONENT_TYPE='CHIPR0402';
      LEAD_LENGTH='';
      DFM_EXCLUSION='';
      DAY='20210715';
      PARENT_PART_TYPE='Q_RES';
      PARENT_PPT='Q_RES';
      PARENT_PPT_PART='Q_RES_0402LF-5.1,5%,1/16W,CHIP,CS-5102JB02';
  end_body;
end_primitive;
primitive 'Q_RES_0402LF-5.36K,1%,1/16W,CHA';
  pin
    'A':
      PIN_GROUP='1';
      PIN_NUMBER='(1)';
      PIN_TYPE='UNSPEC';
      PINUSE='UNSPEC';
    'B':
      PIN_GROUP='1';
      PIN_NUMBER='(2)';
      PIN_TYPE='UNSPEC';
      PINUSE='UNSPEC';
  end_pin;
  body
      PART_NAME='Q_RES';
      PHYS_DES_PREFIX='R';
      STANDARD='End of Design';
      LIFECYCLE='Comp-Approve';
      JEDEC_TYPE='R0402';
      ALT_SYMBOLS='(R0402-0201)';
      VALUE='5.36K';
      TOL='1%';
      WATTAGE='1/16W';
      CLASS='DISCRETE';
      DESCRIPTION='RES CHIP 5.36K 1/16W +-1%(0402)EF';
      COMPONENT_TYPE='CHIPR0402';
      LEAD_LENGTH='';
      DFM_EXCLUSION='';
      DAY='20190906';
      PARENT_PART_TYPE='Q_RES';
      PARENT_PPT='Q_RES';
      PARENT_PPT_PART='Q_RES_0402LF-5.36K,1%,1/16W,CHIP,CS25362FB02';
  end_body;
end_primitive;
primitive 'Q_RES_0402LF-5.49K,1%,1/16W,CHA';
  pin
    'A':
      PIN_GROUP='1';
      PIN_NUMBER='(1)';
      PIN_TYPE='UNSPEC';
      PINUSE='UNSPEC';
    'B':
      PIN_GROUP='1';
      PIN_NUMBER='(2)';
      PIN_TYPE='UNSPEC';
      PINUSE='UNSPEC';
  end_pin;
  body
      PART_NAME='Q_RES';
      PHYS_DES_PREFIX='R';
      STANDARD='End of Design';
      LIFECYCLE='Comp-Approve';
      JEDEC_TYPE='R0402';
      ALT_SYMBOLS='(R0402-0201)';
      VALUE='5.49K';
      TOL='1%';
      WATTAGE='1/16W';
      CLASS='DISCRETE';
      DESCRIPTION='RES CHIP 5.49K 1/16W +-1%(0402) EF';
      COMPONENT_TYPE='CHIPR0402';
      LEAD_LENGTH='';
      DFM_EXCLUSION='';
      DAY='20210804';
      PARENT_PART_TYPE='Q_RES';
      PARENT_PPT='Q_RES';
      PARENT_PPT_PART='Q_RES_0402LF-5.49K,1%,1/16W,CHIP,CS25492FB02';
  end_body;
end_primitive;
primitive 'Q_RES_0402LF-56K,1%,1/16W,CHIPA';
  pin
    'A':
      PIN_GROUP='1';
      PIN_NUMBER='(1)';
      PIN_TYPE='UNSPEC';
      PINUSE='UNSPEC';
    'B':
      PIN_GROUP='1';
      PIN_NUMBER='(2)';
      PIN_TYPE='UNSPEC';
      PINUSE='UNSPEC';
  end_pin;
  body
      PART_NAME='Q_RES';
      PHYS_DES_PREFIX='R';
      STANDARD='';
      LIFECYCLE='';
      JEDEC_TYPE='R0402';
      ALT_SYMBOLS='(R0402-0201)';
      VALUE='56K';
      TOL='1%';
      WATTAGE='1/16W';
      CLASS='DISCRETE';
      DESCRIPTION='RES CHIP 56K 1/16W +-1%(0402)EF';
      COMPONENT_TYPE='CHIPR0402';
      LEAD_LENGTH='';
      DFM_EXCLUSION='';
      DAY='20190711';
      PARENT_PART_TYPE='Q_RES';
      PARENT_PPT='Q_RES';
      PARENT_PPT_PART='Q_RES_0402LF-56K,1%,1/16W,CHIP,CS35602FB00';
  end_body;
end_primitive;
primitive 'Q_RES_0402LF-60.4,1%,1/16W,CHIA';
  pin
    'A':
      PIN_GROUP='1';
      PIN_NUMBER='(1)';
      PIN_TYPE='UNSPEC';
      PINUSE='UNSPEC';
    'B':
      PIN_GROUP='1';
      PIN_NUMBER='(2)';
      PIN_TYPE='UNSPEC';
      PINUSE='UNSPEC';
  end_pin;
  body
      PART_NAME='Q_RES';
      PHYS_DES_PREFIX='R';
      STANDARD='End of Design';
      LIFECYCLE='Comp-Approve';
      JEDEC_TYPE='R0402';
      ALT_SYMBOLS='(R0402-0201)';
      VALUE='60.4';
      TOL='1%';
      WATTAGE='1/16W';
      CLASS='DISCRETE';
      DESCRIPTION='RES CHIP 60.4 1/16W +-1%(0402)EF';
      COMPONENT_TYPE='CHIPR0402';
      LEAD_LENGTH='';
      DFM_EXCLUSION='';
      DAY='20180221';
      PARENT_PART_TYPE='Q_RES';
      PARENT_PPT='Q_RES';
      PARENT_PPT_PART='Q_RES_0402LF-60.4,1%,1/16W,CHIP,CS06042FB03';
  end_body;
end_primitive;
primitive 'Q_RES_0402LF-60.4K,1%,1/16W,CHA';
  pin
    'A':
      PIN_GROUP='1';
      PIN_NUMBER='(1)';
      PIN_TYPE='UNSPEC';
      PINUSE='UNSPEC';
    'B':
      PIN_GROUP='1';
      PIN_NUMBER='(2)';
      PIN_TYPE='UNSPEC';
      PINUSE='UNSPEC';
  end_pin;
  body
      PART_NAME='Q_RES';
      PHYS_DES_PREFIX='R';
      STANDARD='End of Design';
      LIFECYCLE='Comp-Approve';
      JEDEC_TYPE='R0402';
      ALT_SYMBOLS='(R0402-0201)';
      VALUE='60.4K';
      TOL='1%';
      WATTAGE='1/16W';
      CLASS='DISCRETE';
      DESCRIPTION='RES CHIP 60.4K 1/16W +-1%(0402)EF';
      COMPONENT_TYPE='CHIP0402';
      LEAD_LENGTH='';
      DFM_EXCLUSION='';
      DAY='20180212';
      PARENT_PART_TYPE='Q_RES';
      PARENT_PPT='Q_RES';
      PARENT_PPT_PART='Q_RES_0402LF-60.4K,1%,1/16W,CHIP,CS36042FB04';
  end_body;
end_primitive;
primitive 'Q_RES_0402LF-665,1%,1/16W,CHIPA';
  pin
    'A':
      PIN_GROUP='1';
      PIN_NUMBER='(1)';
      PIN_TYPE='UNSPEC';
      PINUSE='UNSPEC';
    'B':
      PIN_GROUP='1';
      PIN_NUMBER='(2)';
      PIN_TYPE='UNSPEC';
      PINUSE='UNSPEC';
  end_pin;
  body
      PART_NAME='Q_RES';
      PHYS_DES_PREFIX='R';
      STANDARD='End of Design';
      LIFECYCLE='Comp-Approve';
      JEDEC_TYPE='R0402';
      ALT_SYMBOLS='(R0402-0201)';
      VALUE='665';
      TOL='1%';
      WATTAGE='1/16W';
      CLASS='DISCRETE';
      DESCRIPTION='RES CHIP 665 1/16W +-1%(0402)EF';
      COMPONENT_TYPE='CHIPR0402';
      LEAD_LENGTH='';
      DFM_EXCLUSION='';
      DAY='20180221';
      PARENT_PART_TYPE='Q_RES';
      PARENT_PPT='Q_RES';
      PARENT_PPT_PART='Q_RES_0402LF-665,1%,1/16W,CHIP,CS16652FB00';
  end_body;
end_primitive;
primitive 'Q_RES_0402LF-68.1,1%,1/16W,CHIA';
  pin
    'A':
      PIN_GROUP='1';
      PIN_NUMBER='(1)';
      PIN_TYPE='UNSPEC';
      PINUSE='UNSPEC';
    'B':
      PIN_GROUP='1';
      PIN_NUMBER='(2)';
      PIN_TYPE='UNSPEC';
      PINUSE='UNSPEC';
  end_pin;
  body
      PART_NAME='Q_RES';
      PHYS_DES_PREFIX='R';
      STANDARD='End of Design';
      LIFECYCLE='Comp-Approve';
      JEDEC_TYPE='R0402';
      ALT_SYMBOLS='(R0402-0201)';
      VALUE='68.1';
      TOL='1%';
      WATTAGE='1/16W';
      CLASS='DISCRETE';
      DESCRIPTION='RES CHIP 68.1 1/16W +-1%(0402)EF';
      COMPONENT_TYPE='CHIPR0402';
      LEAD_LENGTH='';
      DFM_EXCLUSION='';
      DAY='20220421';
      PARENT_PART_TYPE='Q_RES';
      PARENT_PPT='Q_RES';
      PARENT_PPT_PART='Q_RES_0402LF-68.1,1%,1/16W,CHIP,CS06812FB03';
  end_body;
end_primitive;
primitive 'Q_RES_0402LF-681K,1%,1/16W,CHIA';
  pin
    'A':
      PIN_GROUP='1';
      PIN_NUMBER='(1)';
      PIN_TYPE='UNSPEC';
      PINUSE='UNSPEC';
    'B':
      PIN_GROUP='1';
      PIN_NUMBER='(2)';
      PIN_TYPE='UNSPEC';
      PINUSE='UNSPEC';
  end_pin;
  body
      PART_NAME='Q_RES';
      PHYS_DES_PREFIX='R';
      STANDARD='';
      LIFECYCLE='';
      JEDEC_TYPE='R0402';
      ALT_SYMBOLS='(R0402-0201)';
      VALUE='681K';
      TOL='1%';
      WATTAGE='1/16W';
      CLASS='DISCRETE';
      DESCRIPTION='RES CHIP 681K 1/16W +-1%(0402)EF';
      COMPONENT_TYPE='CHIPR0402';
      LEAD_LENGTH='';
      DFM_EXCLUSION='';
      DAY='20190731';
      PARENT_PART_TYPE='Q_RES';
      PARENT_PPT='Q_RES';
      PARENT_PPT_PART='Q_RES_0402LF-681K,1%,1/16W,CHIP,CS46812FB06';
  end_body;
end_primitive;
primitive 'Q_RES_0402LF-75,1%,1/16W,CHIP,A';
  pin
    'A':
      PIN_GROUP='1';
      PIN_NUMBER='(1)';
      PIN_TYPE='UNSPEC';
      PINUSE='UNSPEC';
    'B':
      PIN_GROUP='1';
      PIN_NUMBER='(2)';
      PIN_TYPE='UNSPEC';
      PINUSE='UNSPEC';
  end_pin;
  body
      PART_NAME='Q_RES';
      PHYS_DES_PREFIX='R';
      STANDARD='End of Design';
      LIFECYCLE='Comp-Approve';
      JEDEC_TYPE='R0402';
      ALT_SYMBOLS='(R0402-0201)';
      VALUE='75';
      TOL='1%';
      WATTAGE='1/16W';
      CLASS='DISCRETE';
      DESCRIPTION='RES CHIP 75 1/16W +-1%(0402)EF';
      COMPONENT_TYPE='CHIPR0402';
      LEAD_LENGTH='';
      DFM_EXCLUSION='';
      DAY='20180221';
      PARENT_PART_TYPE='Q_RES';
      PARENT_PPT='Q_RES';
      PARENT_PPT_PART='Q_RES_0402LF-75,1%,1/16W,CHIP,CS07502FB04';
  end_body;
end_primitive;
primitive 'Q_RES_0402LF-750,1%,1/16W,CHIPA';
  pin
    'A':
      PIN_GROUP='1';
      PIN_NUMBER='(1)';
      PIN_TYPE='UNSPEC';
      PINUSE='UNSPEC';
    'B':
      PIN_GROUP='1';
      PIN_NUMBER='(2)';
      PIN_TYPE='UNSPEC';
      PINUSE='UNSPEC';
  end_pin;
  body
      PART_NAME='Q_RES';
      PHYS_DES_PREFIX='R';
      STANDARD='End of Design';
      LIFECYCLE='Comp-Approve';
      JEDEC_TYPE='R0402';
      ALT_SYMBOLS='(R0402-0201)';
      VALUE='750';
      TOL='1%';
      WATTAGE='1/16W';
      CLASS='DISCRETE';
      DESCRIPTION='RES CHIP 750 1/16W +-1%(0402)EF';
      COMPONENT_TYPE='CHIPR0402';
      LEAD_LENGTH='';
      DFM_EXCLUSION='';
      DAY='20191227';
      PARENT_PART_TYPE='Q_RES';
      PARENT_PPT='Q_RES';
      PARENT_PPT_PART='Q_RES_0402LF-750,1%,1/16W,CHIP,CS17502FB03';
  end_body;
end_primitive;
primitive 'Q_RES_0402LF-8.2K,5%,1/16W,CHIA';
  pin
    'A':
      PIN_GROUP='1';
      PIN_NUMBER='(1)';
      PIN_TYPE='UNSPEC';
      PINUSE='UNSPEC';
    'B':
      PIN_GROUP='1';
      PIN_NUMBER='(2)';
      PIN_TYPE='UNSPEC';
      PINUSE='UNSPEC';
  end_pin;
  body
      PART_NAME='Q_RES';
      PHYS_DES_PREFIX='R';
      STANDARD='End of Design';
      LIFECYCLE='Comp-Approve';
      JEDEC_TYPE='R0402';
      ALT_SYMBOLS='(R0402-0201)';
      VALUE='8.2K';
      TOL='5%';
      WATTAGE='1/16W';
      CLASS='DISCRETE';
      DESCRIPTION='RES CHIP 8.2K 1/16W +-5% (0402) EF';
      COMPONENT_TYPE='CHIP0402';
      LEAD_LENGTH='';
      DFM_EXCLUSION='';
      DAY='20180212';
      PARENT_PART_TYPE='Q_RES';
      PARENT_PPT='Q_RES';
      PARENT_PPT_PART='Q_RES_0402LF-8.2K,5%,1/16W,CHIP,CS28202JB05';
  end_body;
end_primitive;
primitive 'Q_RES_0402LF-8.2K,5%,1/16W,EMPA';
  pin
    'A':
      PIN_GROUP='1';
      PIN_NUMBER='(1)';
      PIN_TYPE='UNSPEC';
      PINUSE='UNSPEC';
    'B':
      PIN_GROUP='1';
      PIN_NUMBER='(2)';
      PIN_TYPE='UNSPEC';
      PINUSE='UNSPEC';
  end_pin;
  body
      PART_NAME='Q_RES';
      PHYS_DES_PREFIX='R';
      STANDARD='End of Design';
      LIFECYCLE='Comp-Approve';
      JEDEC_TYPE='R0402';
      ALT_SYMBOLS='(R0402-0201)';
      VALUE='8.2K';
      TOL='5%';
      WATTAGE='1/16W';
      CLASS='IO';
      DESCRIPTION='RES CHIP 8.2K 1/16W +-5% (0402) EF';
      COMPONENT_TYPE='CHIP0402';
      LEAD_LENGTH='';
      DFM_EXCLUSION='';
      DAY='20180212';
      PARENT_PART_TYPE='Q_RES';
      PARENT_PPT='Q_RES';
      PARENT_PPT_PART='Q_RES_0402LF-8.2K,5%,1/16W,EMPTY,CS28202JB05';
  end_body;
end_primitive;
primitive 'Q_RES_0402LF-90.9,1%,1/16W,CHIA';
  pin
    'A':
      PIN_GROUP='1';
      PIN_NUMBER='(1)';
      PIN_TYPE='UNSPEC';
      PINUSE='UNSPEC';
    'B':
      PIN_GROUP='1';
      PIN_NUMBER='(2)';
      PIN_TYPE='UNSPEC';
      PINUSE='UNSPEC';
  end_pin;
  body
      PART_NAME='Q_RES';
      PHYS_DES_PREFIX='R';
      STANDARD='End of Design';
      LIFECYCLE='Comp-Approve';
      JEDEC_TYPE='R0402';
      ALT_SYMBOLS='(R0402-0201)';
      VALUE='90.9';
      TOL='1%';
      WATTAGE='1/16W';
      CLASS='DISCRETE';
      DESCRIPTION='RES CHIP 90.9 1/16W +-1%(0402)';
      COMPONENT_TYPE='CHIP0402';
      LEAD_LENGTH='';
      DFM_EXCLUSION='';
      DAY='20120221';
      PARENT_PART_TYPE='Q_RES';
      PARENT_PPT='Q_RES';
      PARENT_PPT_PART='Q_RES_0402LF-90.9,1%,1/16W,CHIP,CS09092FB15';
  end_body;
end_primitive;
primitive 'Q_RES_0402LF-91K,1%,1/16W,CHIPA';
  pin
    'A':
      PIN_GROUP='1';
      PIN_NUMBER='(1)';
      PIN_TYPE='UNSPEC';
      PINUSE='UNSPEC';
    'B':
      PIN_GROUP='1';
      PIN_NUMBER='(2)';
      PIN_TYPE='UNSPEC';
      PINUSE='UNSPEC';
  end_pin;
  body
      PART_NAME='Q_RES';
      PHYS_DES_PREFIX='R';
      STANDARD='';
      LIFECYCLE='';
      JEDEC_TYPE='R0402';
      ALT_SYMBOLS='(R0402-0201)';
      VALUE='91K';
      TOL='1%';
      WATTAGE='1/16W';
      CLASS='DISCRETE';
      DESCRIPTION='RES CHIP 91K 1/16W +-1%(0402)EF';
      COMPONENT_TYPE='CHIPR0402';
      LEAD_LENGTH='';
      DFM_EXCLUSION='';
      DAY='20200602';
      PARENT_PART_TYPE='Q_RES';
      PARENT_PPT='Q_RES';
      PARENT_PPT_PART='Q_RES_0402LF-91K,1%,1/16W,CHIP,CS39102FB06';
  end_body;
end_primitive;
primitive 'Q_RES_0603LF-0,5%,1/10W,EMPTY,A';
  pin
    'A':
      PIN_GROUP='1';
      PIN_NUMBER='(1)';
      PIN_TYPE='UNSPEC';
      PINUSE='UNSPEC';
    'B':
      PIN_GROUP='1';
      PIN_NUMBER='(2)';
      PIN_TYPE='UNSPEC';
      PINUSE='UNSPEC';
  end_pin;
  body
      PART_NAME='Q_RES';
      PHYS_DES_PREFIX='R';
      STANDARD='End of Design';
      LIFECYCLE='Comp-Approve';
      JEDEC_TYPE='R0603';
      ALT_SYMBOLS='(SMR0603AW)';
      VALUE='0';
      TOL='5%';
      WATTAGE='1/16W';
      CLASS='IO';
      DESCRIPTION='RES CHIP 0 1/10W +-5% (0603)EF';
      COMPONENT_TYPE='CHIPR0603';
      LEAD_LENGTH='';
      DFM_EXCLUSION='';
      DAY='20180208';
      PARENT_PART_TYPE='Q_RES';
      PARENT_PPT='Q_RES';
      PARENT_PPT_PART='Q_RES_0603LF-0,5%,1/10W,EMPTY,CS00003J910';
  end_body;
end_primitive;
primitive 'RT9059GQW-RT9059GQW,SMLF,IC,ALA';
  pin
    'PGOOD':
      PIN_NUMBER='(5)';
      OUTPUT_LOAD='(1.0,-1.0)';
      PINUSE='OUT';
    'EN':
      PIN_NUMBER='(6)';
      INPUT_LOAD='(-0.01,0.01)';
      PINUSE='IN';
    'ADJ':
      PIN_NUMBER='(4)';
      INPUT_LOAD='(-0.01,0.01)';
      PINUSE='IN';
    'VOUT1':
      PIN_NUMBER='(1)';
      OUTPUT_LOAD='(1.0,-1.0)';
      PINUSE='OUT';
    'VIN1':
      PIN_NUMBER='(7)';
      INPUT_LOAD='(-0.01,0.01)';
      PINUSE='IN';
    'VDD':
      PIN_NUMBER='(10)';
      INPUT_LOAD='(-0.01,0.01)';
      PINUSE='IN';
    'EP':
      PIN_NUMBER='(TH)';
      PINUSE='POWER';
      NO_LOAD_CHECK='Both';
      NO_IO_CHECK='Both';
      NO_ASSERT_CHECK='TRUE';
      NO_DIR_CHECK='TRUE';
      ALLOW_CONNECT='TRUE';
    'VOUT2':
      PIN_NUMBER='(2)';
      OUTPUT_LOAD='(1.0,-1.0)';
      PINUSE='OUT';
    'VOUT3':
      PIN_NUMBER='(3)';
      OUTPUT_LOAD='(1.0,-1.0)';
      PINUSE='OUT';
    'VIN2':
      PIN_NUMBER='(8)';
      INPUT_LOAD='(-0.01,0.01)';
      PINUSE='IN';
    'VIN3':
      PIN_NUMBER='(9)';
      INPUT_LOAD='(-0.01,0.01)';
      PINUSE='IN';
  end_pin;
  body
      PART_NAME='RT9059GQW';
      BODY_NAME='RT9059GQW';
      PHYS_DES_PREFIX='U';
      CLASS='IC';
      STANDARD='';
      LIFECYCLE='';
      JEDEC_TYPE='DFN10_THXE';
      DESCRIPTION='IC OTHER(10P) RT9059GQW(WDFN)';
      MANUFTR='RTK';
      MANUF_PN='RT9059GQW';
      RD_CMPLS_LVL='EP(V1)';
      CMPLS_LVL='';
      FROM_PJ='S4E-ALAN';
      DIP_SMD='';
      DATA='RTK_RT9059_rev2012.pdf';
      EE_CHECK_LIST='';
      FP_ECN='';
      PSL='';
      CREATOR='';
      STATUS='';
      CREATEDAY='20120514';
      PARENT_PART_TYPE='RT9059GQW';
      PARENT_PPT='RT9059GQW';
      PARENT_PPT_PART='RT9059GQW-RT9059GQW,SMLF,IC,AL009059000';
  end_body;
end_primitive;
primitive 'SCHOTTKY_12-1N5819HW,SMLF,IC,BA';
  pin
    'A':
      PIN_NUMBER='(1)';
      INPUT_LOAD='(-0.01,0.01)';
      PINUSE='IN';
    'C':
      PIN_NUMBER='(2)';
      BIDIRECTIONAL='TRUE';
      INPUT_LOAD='(-0.01,0.01)';
      OUTPUT_LOAD='(1.0,-1.0)';
      PINUSE='BI';
  end_pin;
  body
      PART_NAME='SCHOTTKY_12';
      BODY_NAME='SCHOTTKY_12';
      PHYS_DES_PREFIX='D';
      CLASS='IC';
      STANDARD='End of Design';
      LIFECYCLE='Comp-Approve';
      JEDEC_TYPE='SOD123';
      DESCRIPTION='DIODE SMD 1N5819HW-7-F(40V.1A.SOD123)';
      MANUFTR='DDS';
      MANUF_PN='1N5819HW-7-F';
      RD_CMPLS_LVL='';
      CMPLS_LVL='EP';
      DIP_SMD='';
      FP_ECN='';
      FROM_PJ='T2H-WADE';
      DATA='DDS_1N5819HW.pdf';
      EE_CHECK_LIST='';
      STATUS='';
      PSL='';
      PREFERENCE='';
      CREATOR='';
      CREATEDAY='20151228';
      PARENT_PART_TYPE='SCHOTTKY_12';
      PARENT_PPT='SCHOTTKY_12';
      PARENT_PPT_PART='SCHOTTKY_12-1N5819HW,SMLF,IC,BC005819Z40';
  end_body;
end_primitive;
primitive 'SCHOTTKY_12-SBA130Q,SMLF,EMPTYA';
  pin
    'A':
      PIN_NUMBER='(1)';
      INPUT_LOAD='(-0.01,0.01)';
      PINUSE='IN';
    'C':
      PIN_NUMBER='(2)';
      BIDIRECTIONAL='TRUE';
      INPUT_LOAD='(-0.01,0.01)';
      OUTPUT_LOAD='(1.0,-1.0)';
      PINUSE='BI';
  end_pin;
  body
      PART_NAME='SCHOTTKY_12';
      BODY_NAME='SCHOTTKY_12';
      PHYS_DES_PREFIX='D';
      CLASS='IC';
      STANDARD='';
      LIFECYCLE='';
      JEDEC_TYPE='DFN1610-2_1-6X1';
      DESCRIPTION='DIODE SMD SBA130Q(30V,1A,SCHOTTKY)';
      MANUFTR='PJT';
      MANUF_PN='SBA130Q';
      RD_CMPLS_LVL='EP(V1)';
      CMPLS_LVL='';
      DIP_SMD='';
      FP_ECN='';
      FROM_PJ='S6A-HANK';
      DATA='PJT_SBA130Q.pdf';
      EE_CHECK_LIST='';
      STATUS='';
      PSL='';
      PREFERENCE='';
      CREATOR='';
      CREATEDAY='20180508';
      PARENT_PART_TYPE='SCHOTTKY_12';
      PARENT_PPT='SCHOTTKY_12';
      PARENT_PPT_PART='SCHOTTKY_12-SBA130Q,SMLF,EMPTY,BCSBA130Z00';
  end_body;
end_primitive;
primitive 'SCHOTTKY_AC-SS0530,SMLF,EMPTY,A';
  pin
    'A':
      PIN_NUMBER='(A)';
      INPUT_LOAD='(-0.01,0.01)';
      PINUSE='IN';
    'C':
      PIN_NUMBER='(C)';
      BIDIRECTIONAL='TRUE';
      INPUT_LOAD='(-0.01,0.01)';
      OUTPUT_LOAD='(1.0,-1.0)';
      PINUSE='BI';
  end_pin;
  body
      PART_NAME='SCHOTTKY_AC';
      BODY_NAME='SCHOTTKY_AC';
      PHYS_DES_PREFIX='D';
      CLASS='IC';
      STANDARD='';
      LIFECYCLE='';
      JEDEC_TYPE='SOD123XD';
      DESCRIPTION='DIODE SMD SS0530(30V,0.5A)SOD-123';
      MANUFTR='PJT';
      MANUF_PN='SS0530';
      RD_CMPLS_LVL='EP(V1)';
      CMPLS_LVL='';
      DIP_SMD='';
      FP_ECN='';
      FROM_PJ='S1D-OZ';
      DATA='PJT_SS0520-SS0540.pdf';
      EE_CHECK_LIST='';
      PSL='';
      PREFERENCE='';
      CREATOR='';
      CREATEDAY='20120915';
      STATUS='';
      PARENT_PART_TYPE='SCHOTTKY_AC';
      PARENT_PPT='SCHOTTKY_AC';
      PARENT_PPT_PART='SCHOTTKY_AC-SS0530,SMLF,EMPTY,BCSS0530Z00';
  end_body;
end_primitive;
primitive 'SCHOTTKY_AC-SS0530,SMLF,IC,BCSA';
  pin
    'A':
      PIN_NUMBER='(A)';
      INPUT_LOAD='(-0.01,0.01)';
      PINUSE='IN';
    'C':
      PIN_NUMBER='(C)';
      BIDIRECTIONAL='TRUE';
      INPUT_LOAD='(-0.01,0.01)';
      OUTPUT_LOAD='(1.0,-1.0)';
      PINUSE='BI';
  end_pin;
  body
      PART_NAME='SCHOTTKY_AC';
      BODY_NAME='SCHOTTKY_AC';
      PHYS_DES_PREFIX='D';
      CLASS='IC';
      STANDARD='';
      LIFECYCLE='';
      JEDEC_TYPE='SOD123XD';
      DESCRIPTION='DIODE SMD SS0530(30V,0.5A)SOD-123';
      MANUFTR='PJT';
      MANUF_PN='SS0530';
      RD_CMPLS_LVL='EP(V1)';
      CMPLS_LVL='';
      DIP_SMD='';
      FP_ECN='';
      FROM_PJ='S1D-OZ';
      DATA='PJT_SS0520-SS0540.pdf';
      EE_CHECK_LIST='';
      PSL='';
      PREFERENCE='';
      CREATOR='';
      CREATEDAY='20120915';
      STATUS='';
      PARENT_PART_TYPE='SCHOTTKY_AC';
      PARENT_PPT='SCHOTTKY_AC';
      PARENT_PPT_PART='SCHOTTKY_AC-SS0530,SMLF,IC,BCSS0530Z00';
  end_body;
end_primitive;
primitive 'SCONN11_9192031111LF-SCONN11_9A';
  pin
    '1':
      PIN_NUMBER='(1)';
      BIDIRECTIONAL='TRUE';
      INPUT_LOAD='(-0.01,0.01)';
      OUTPUT_LOAD='(1.0,-1.0)';
      PINUSE='BI';
    '3':
      PIN_NUMBER='(3)';
      BIDIRECTIONAL='TRUE';
      INPUT_LOAD='(-0.01,0.01)';
      OUTPUT_LOAD='(1.0,-1.0)';
      PINUSE='BI';
    '4':
      PIN_NUMBER='(4)';
      BIDIRECTIONAL='TRUE';
      INPUT_LOAD='(-0.01,0.01)';
      OUTPUT_LOAD='(1.0,-1.0)';
      PINUSE='BI';
    '5':
      PIN_NUMBER='(5)';
      BIDIRECTIONAL='TRUE';
      INPUT_LOAD='(-0.01,0.01)';
      OUTPUT_LOAD='(1.0,-1.0)';
      PINUSE='BI';
    '2':
      PIN_NUMBER='(2)';
      BIDIRECTIONAL='TRUE';
      INPUT_LOAD='(-0.01,0.01)';
      OUTPUT_LOAD='(1.0,-1.0)';
      PINUSE='BI';
    'G1':
      PIN_NUMBER='(G1)';
      PINUSE='POWER';
      NO_LOAD_CHECK='Both';
      NO_IO_CHECK='Both';
      NO_ASSERT_CHECK='TRUE';
      NO_DIR_CHECK='TRUE';
      ALLOW_CONNECT='TRUE';
    'G2':
      PIN_NUMBER='(G2)';
      PINUSE='POWER';
      NO_LOAD_CHECK='Both';
      NO_IO_CHECK='Both';
      NO_ASSERT_CHECK='TRUE';
      NO_DIR_CHECK='TRUE';
      ALLOW_CONNECT='TRUE';
    '6':
      PIN_NUMBER='(6)';
      BIDIRECTIONAL='TRUE';
      INPUT_LOAD='(-0.01,0.01)';
      OUTPUT_LOAD='(1.0,-1.0)';
      PINUSE='BI';
    '7':
      PIN_NUMBER='(7)';
      BIDIRECTIONAL='TRUE';
      INPUT_LOAD='(-0.01,0.01)';
      OUTPUT_LOAD='(1.0,-1.0)';
      PINUSE='BI';
    '8':
      PIN_NUMBER='(8)';
      BIDIRECTIONAL='TRUE';
      INPUT_LOAD='(-0.01,0.01)';
      OUTPUT_LOAD='(1.0,-1.0)';
      PINUSE='BI';
    '9':
      PIN_NUMBER='(9)';
      BIDIRECTIONAL='TRUE';
      INPUT_LOAD='(-0.01,0.01)';
      OUTPUT_LOAD='(1.0,-1.0)';
      PINUSE='BI';
    '10':
      PIN_NUMBER='(10)';
      BIDIRECTIONAL='TRUE';
      INPUT_LOAD='(-0.01,0.01)';
      OUTPUT_LOAD='(1.0,-1.0)';
      PINUSE='BI';
    '11':
      PIN_NUMBER='(11)';
      BIDIRECTIONAL='TRUE';
      INPUT_LOAD='(-0.01,0.01)';
      OUTPUT_LOAD='(1.0,-1.0)';
      PINUSE='BI';
  end_pin;
  body
      PART_NAME='SCONN11_9192031111LF';
      BODY_NAME='SCONN11_9192031111LF';
      PHYS_DES_PREFIX='J';
      CLASS='IO';
      STANDARD='';
      LIFECYCLE='';
      JEDEC_TYPE='CON_F11S2H2S_P1W4-22_LDH';
      DESCRIPTION='CONN SMD HOUSING 11P 2R FS(P1,H3.28)';
      MANUFTR='BER';
      MANUF_PN='91920-31111LF';
      RD_CMPLS_LVL='EP(V1)';
      CMPLS_LVL='EP(V1)';
      DIP_SMD='';
      FROM_PJ='S9N-CY';
      DATA='BER_91920-31111LF.pdf';
      FP_ECN='';
      EE_CHECK_LIST='';
      CREATOR='';
      CREATEDAY='20181102';
      PSL='';
      STATUS='';
      ESD_CDM='NA';
      ESD_HBM='NA';
      ESD_MM='NA';
      MSD='NA';
      PIN_LENGTH_LONG_PIN='0 MILS';
      PIN_LENGTH_SHORT_PIN='0 MILS';
      PARENT_PART_TYPE='SCONN11_9192031111LF';
      PARENT_PPT='SCONN11_9192031111LF';
      PARENT_PPT_PART='SCONN11_9192031111LF-SCONN11_91920-31111LF,SMLF,IO,DFHS11FS009';
  end_body;
end_primitive;
primitive 'SCONN13_502280130CV01-SCONN13_A';
  pin
    '1':
      PIN_NUMBER='(1)';
      BIDIRECTIONAL='TRUE';
      INPUT_LOAD='(-0.01,0.01)';
      OUTPUT_LOAD='(1.0,-1.0)';
      PINUSE='BI';
    '2':
      PIN_NUMBER='(2)';
      BIDIRECTIONAL='TRUE';
      INPUT_LOAD='(-0.01,0.01)';
      OUTPUT_LOAD='(1.0,-1.0)';
      PINUSE='BI';
    '3':
      PIN_NUMBER='(3)';
      BIDIRECTIONAL='TRUE';
      INPUT_LOAD='(-0.01,0.01)';
      OUTPUT_LOAD='(1.0,-1.0)';
      PINUSE='BI';
    '4':
      PIN_NUMBER='(4)';
      BIDIRECTIONAL='TRUE';
      INPUT_LOAD='(-0.01,0.01)';
      OUTPUT_LOAD='(1.0,-1.0)';
      PINUSE='BI';
    '5':
      PIN_NUMBER='(5)';
      BIDIRECTIONAL='TRUE';
      INPUT_LOAD='(-0.01,0.01)';
      OUTPUT_LOAD='(1.0,-1.0)';
      PINUSE='BI';
    '6':
      PIN_NUMBER='(6)';
      BIDIRECTIONAL='TRUE';
      INPUT_LOAD='(-0.01,0.01)';
      OUTPUT_LOAD='(1.0,-1.0)';
      PINUSE='BI';
    '7':
      PIN_NUMBER='(7)';
      BIDIRECTIONAL='TRUE';
      INPUT_LOAD='(-0.01,0.01)';
      OUTPUT_LOAD='(1.0,-1.0)';
      PINUSE='BI';
    '8':
      PIN_NUMBER='(8)';
      BIDIRECTIONAL='TRUE';
      INPUT_LOAD='(-0.01,0.01)';
      OUTPUT_LOAD='(1.0,-1.0)';
      PINUSE='BI';
    '9':
      PIN_NUMBER='(9)';
      BIDIRECTIONAL='TRUE';
      INPUT_LOAD='(-0.01,0.01)';
      OUTPUT_LOAD='(1.0,-1.0)';
      PINUSE='BI';
    '10':
      PIN_NUMBER='(10)';
      BIDIRECTIONAL='TRUE';
      INPUT_LOAD='(-0.01,0.01)';
      OUTPUT_LOAD='(1.0,-1.0)';
      PINUSE='BI';
    '11':
      PIN_NUMBER='(11)';
      BIDIRECTIONAL='TRUE';
      INPUT_LOAD='(-0.01,0.01)';
      OUTPUT_LOAD='(1.0,-1.0)';
      PINUSE='BI';
    '12':
      PIN_NUMBER='(12)';
      BIDIRECTIONAL='TRUE';
      INPUT_LOAD='(-0.01,0.01)';
      OUTPUT_LOAD='(1.0,-1.0)';
      PINUSE='BI';
    '13':
      PIN_NUMBER='(13)';
      BIDIRECTIONAL='TRUE';
      INPUT_LOAD='(-0.01,0.01)';
      OUTPUT_LOAD='(1.0,-1.0)';
      PINUSE='BI';
    'G1':
      PIN_NUMBER='(G1)';
      PINUSE='POWER';
      NO_LOAD_CHECK='Both';
      NO_IO_CHECK='Both';
      NO_ASSERT_CHECK='TRUE';
      NO_DIR_CHECK='TRUE';
      ALLOW_CONNECT='TRUE';
    'G2':
      PIN_NUMBER='(G2)';
      PINUSE='POWER';
      NO_LOAD_CHECK='Both';
      NO_IO_CHECK='Both';
      NO_ASSERT_CHECK='TRUE';
      NO_DIR_CHECK='TRUE';
      ALLOW_CONNECT='TRUE';
  end_pin;
  body
      PART_NAME='SCONN13_502280130CV01';
      BODY_NAME='SCONN13_502280130CV01';
      PHYS_DES_PREFIX='J';
      CLASS='IO';
      STANDARD='';
      LIFECYCLE='';
      JEDEC_TYPE='CON_13S1H2S_P1XA';
      DESCRIPTION='CONN SMD HEADER 13P 1R MS(P1.0,H4.3)';
      MANUFTR='ACS';
      MANUF_PN='50228-0130C-V01';
      RD_CMPLS_LVL='EP(V1)';
      CMPLS_LVL='';
      DIP_SMD='';
      FROM_PJ='S5C-YAN';
      DATA='ACS_50228-0130C-V01.pdf';
      FP_ECN='';
      EE_CHECK_LIST='';
      CREATOR='';
      CREATEDAY='20180315';
      PSL='';
      STATUS='';
      ESD_CDM='NA';
      ESD_HBM='NA';
      ESD_MM='NA';
      MSD='NA';
      PIN_LENGTH_LONG_PIN='0 MILS';
      PIN_LENGTH_SHORT_PIN='0 MILS';
      PARENT_PART_TYPE='SCONN13_502280130CV01';
      PARENT_PPT='SCONN13_502280130CV01';
      PARENT_PPT_PART='SCONN13_502280130CV01-SCONN13_50228-0130C-V01,SMLF,IO,DFHD13MS080';
  end_body;
end_primitive;
primitive 'SCONN16_ACASPI006P06-SCONN16_AA';
  pin
    'VCC':
      PIN_NUMBER='(2)';
      PINUSE='POWER';
      NO_LOAD_CHECK='Both';
      NO_IO_CHECK='Both';
      NO_DIR_CHECK='TRUE';
      NO_ASSERT_CHECK='TRUE';
      ALLOW_CONNECT='TRUE';
    'HOLD_N':
      PIN_NUMBER='(1)';
      BIDIRECTIONAL='TRUE';
      INPUT_LOAD='(-0.01,0.01)';
      OUTPUT_LOAD='(1.0,-1.0)';
      PINUSE='BI';
    'CS_N':
      PIN_NUMBER='(7)';
      BIDIRECTIONAL='TRUE';
      INPUT_LOAD='(-0.01,0.01)';
      OUTPUT_LOAD='(1.0,-1.0)';
      PINUSE='BI';
    'WP_N':
      PIN_NUMBER='(9)';
      BIDIRECTIONAL='TRUE';
      INPUT_LOAD='(-0.01,0.01)';
      OUTPUT_LOAD='(1.0,-1.0)';
      PINUSE='BI';
    'DI':
      PIN_NUMBER='(15)';
      BIDIRECTIONAL='TRUE';
      INPUT_LOAD='(-0.01,0.01)';
      OUTPUT_LOAD='(1.0,-1.0)';
      PINUSE='BI';
    'CLK':
      PIN_NUMBER='(16)';
      BIDIRECTIONAL='TRUE';
      INPUT_LOAD='(-0.01,0.01)';
      OUTPUT_LOAD='(1.0,-1.0)';
      PINUSE='BI';
    'GND':
      PIN_NUMBER='(10)';
      PINUSE='POWER';
      NO_LOAD_CHECK='Both';
      NO_IO_CHECK='Both';
      NO_DIR_CHECK='TRUE';
      NO_ASSERT_CHECK='TRUE';
      ALLOW_CONNECT='TRUE';
    'DO':
      PIN_NUMBER='(8)';
      BIDIRECTIONAL='TRUE';
      INPUT_LOAD='(-0.01,0.01)';
      OUTPUT_LOAD='(1.0,-1.0)';
      PINUSE='BI';
    'NC0':
      PIN_NUMBER='(3)';
      BIDIRECTIONAL='TRUE';
      INPUT_LOAD='(-0.01,0.01)';
      OUTPUT_LOAD='(1.0,-1.0)';
      PINUSE='BI';
    'NC1':
      PIN_NUMBER='(4)';
      BIDIRECTIONAL='TRUE';
      INPUT_LOAD='(-0.01,0.01)';
      OUTPUT_LOAD='(1.0,-1.0)';
      PINUSE='BI';
    'NC2':
      PIN_NUMBER='(5)';
      BIDIRECTIONAL='TRUE';
      INPUT_LOAD='(-0.01,0.01)';
      OUTPUT_LOAD='(1.0,-1.0)';
      PINUSE='BI';
    'NC3':
      PIN_NUMBER='(6)';
      BIDIRECTIONAL='TRUE';
      INPUT_LOAD='(-0.01,0.01)';
      OUTPUT_LOAD='(1.0,-1.0)';
      PINUSE='BI';
    'NC4':
      PIN_NUMBER='(11)';
      BIDIRECTIONAL='TRUE';
      INPUT_LOAD='(-0.01,0.01)';
      OUTPUT_LOAD='(1.0,-1.0)';
      PINUSE='BI';
    'NC6':
      PIN_NUMBER='(12)';
      BIDIRECTIONAL='TRUE';
      INPUT_LOAD='(-0.01,0.01)';
      OUTPUT_LOAD='(1.0,-1.0)';
      PINUSE='BI';
    'NC7':
      PIN_NUMBER='(13)';
      BIDIRECTIONAL='TRUE';
      INPUT_LOAD='(-0.01,0.01)';
      OUTPUT_LOAD='(1.0,-1.0)';
      PINUSE='BI';
    'NC8':
      PIN_NUMBER='(14)';
      BIDIRECTIONAL='TRUE';
      INPUT_LOAD='(-0.01,0.01)';
      OUTPUT_LOAD='(1.0,-1.0)';
      PINUSE='BI';
  end_pin;
  body
      PART_NAME='SCONN16_ACASPI006P06';
      BODY_NAME='SCONN16_ACASPI006P06';
      PHYS_DES_PREFIX='U';
      CLASS='IO';
      STANDARD='';
      LIFECYCLE='';
      JEDEC_TYPE='SOCKET16SXA';
      DESCRIPTION='IC SOCKET SMD 16P(SPI,SOIC)(P1.27,H5.8)';
      MANUFTR='LTS';
      MANUF_PN='ACA-SPI-006-P06';
      RD_CMPLS_LVL='EU(V1)';
      CMPLS_LVL='EP(V1)';
      DIP_SMD='';
      FROM_PJ='T6UB-MC';
      DATA='LTS_ACA-SPI-006-P06.pdf';
      FP_ECN='ACA-SPI-006-P06.msg';
      EE_CHECK_LIST='';
      CREATOR='';
      CREATEDAY='20200811';
      PSL='';
      STATUS='';
      ESD_CDM='NA';
      ESD_HBM='NA';
      ESD_MM='NA';
      MSD='NA';
      PIN_LENGTH_LONG_PIN='0 MILS';
      PIN_LENGTH_SHORT_PIN='0 MILS';
      PARENT_PART_TYPE='SCONN16_ACASPI006P06';
      PARENT_PPT='SCONN16_ACASPI006P06';
      PARENT_PPT_PART='SCONN16_ACASPI006P06-SCONN16_ACA-SPI-006-P06,SMLF,IO,DG016000006';
  end_body;
end_primitive;
primitive 'SCONN3_21291035BR2-SCONN3_212-A';
  pin
    '3':
      PIN_NUMBER='(3)';
      BIDIRECTIONAL='TRUE';
      INPUT_LOAD='(-0.01,0.01)';
      OUTPUT_LOAD='(1.0,-1.0)';
      PINUSE='BI';
    '2':
      PIN_NUMBER='(2)';
      BIDIRECTIONAL='TRUE';
      INPUT_LOAD='(-0.01,0.01)';
      OUTPUT_LOAD='(1.0,-1.0)';
      PINUSE='BI';
    '1':
      PIN_NUMBER='(1)';
      BIDIRECTIONAL='TRUE';
      INPUT_LOAD='(-0.01,0.01)';
      OUTPUT_LOAD='(1.0,-1.0)';
      PINUSE='BI';
  end_pin;
  body
      PART_NAME='SCONN3_21291035BR2';
      BODY_NAME='SCONN3_21291035BR2';
      PHYS_DES_PREFIX='J';
      CLASS='IO';
      STANDARD='';
      LIFECYCLE='';
      JEDEC_TYPE='HEADER1X3SXF';
      DESCRIPTION='CONN SMD HEADER 3P 1R MS(P2.54, H9.3)';
      MANUFTR='PRX';
      MANUF_PN='212-91-035BR2';
      RD_CMPLS_LVL='EU(V1)';
      CMPLS_LVL='EU(V1)';
      DIP_SMD='';
      FROM_PJ='S5XQ-FRANK';
      DATA='PRX_212-91-035BR2.pdf';
      FP_ECN='212-91-035BR2.msg';
      EE_CHECK_LIST='';
      CREATOR='';
      CREATEDAY='20200131';
      PSL='';
      STATUS='';
      ESD_CDM='NA';
      ESD_HBM='NA';
      ESD_MM='NA';
      MSD='NA';
      PIN_LENGTH_LONG_PIN='0 MILS';
      PIN_LENGTH_SHORT_PIN='0 MILS';
      PARENT_PART_TYPE='SCONN3_21291035BR2';
      PARENT_PPT='SCONN3_21291035BR2';
      PARENT_PPT_PART='SCONN3_21291035BR2-SCONN3_212-91-035BR2,SMLF,EMPTY,DFHD03MS251';
  end_body;
end_primitive;
primitive 'SCONN3_212H9103GBR1-SCONN3_212A';
  pin
    '3':
      PIN_NUMBER='(3)';
      BIDIRECTIONAL='TRUE';
      INPUT_LOAD='(-0.01,0.01)';
      OUTPUT_LOAD='(1.0,-1.0)';
      PINUSE='BI';
    '2':
      PIN_NUMBER='(2)';
      BIDIRECTIONAL='TRUE';
      INPUT_LOAD='(-0.01,0.01)';
      OUTPUT_LOAD='(1.0,-1.0)';
      PINUSE='BI';
    '1':
      PIN_NUMBER='(1)';
      BIDIRECTIONAL='TRUE';
      INPUT_LOAD='(-0.01,0.01)';
      OUTPUT_LOAD='(1.0,-1.0)';
      PINUSE='BI';
  end_pin;
  body
      PART_NAME='SCONN3_212H9103GBR1';
      BODY_NAME='SCONN3_212H9103GBR1';
      PHYS_DES_PREFIX='J';
      CLASS='IO';
      STANDARD='';
      LIFECYCLE='';
      JEDEC_TYPE='HEADER1X3SXE_H367';
      DESCRIPTION='CONN SMD HEADER 3P 1R MS(P2.54,H9.3)';
      MANUFTR='PRX';
      MANUF_PN='212-H91-03GBR1';
      RD_CMPLS_LVL='EP(V1)';
      CMPLS_LVL='EP(V1)';
      DIP_SMD='';
      FROM_PJ='S5C-HOWARD';
      DATA='PRX_212-H91-03GBR1.pdf';
      FP_ECN='212-H91-03GBR1.msg';
      EE_CHECK_LIST='';
      CREATOR='';
      CREATEDAY='20200131';
      PSL='';
      STATUS='';
      ESD_CDM='NA';
      ESD_HBM='NA';
      ESD_MM='NA';
      MSD='NA';
      PIN_LENGTH_LONG_PIN='0 MILS';
      PIN_LENGTH_SHORT_PIN='0 MILS';
      PARENT_PART_TYPE='SCONN3_212H9103GBR1';
      PARENT_PPT='SCONN3_212H9103GBR1';
      PARENT_PPT_PART='SCONN3_212H9103GBR1-SCONN3_212-H91-03GBR1,SMLF,IO,DFHD03MS161';
  end_body;
end_primitive;
primitive 'SCONN3_212H9103GBR1-SCONN3_212B';
  pin
    '3':
      PIN_NUMBER='(3)';
      BIDIRECTIONAL='TRUE';
      INPUT_LOAD='(-0.01,0.01)';
      OUTPUT_LOAD='(1.0,-1.0)';
      PINUSE='BI';
    '2':
      PIN_NUMBER='(2)';
      BIDIRECTIONAL='TRUE';
      INPUT_LOAD='(-0.01,0.01)';
      OUTPUT_LOAD='(1.0,-1.0)';
      PINUSE='BI';
    '1':
      PIN_NUMBER='(1)';
      BIDIRECTIONAL='TRUE';
      INPUT_LOAD='(-0.01,0.01)';
      OUTPUT_LOAD='(1.0,-1.0)';
      PINUSE='BI';
  end_pin;
  body
      PART_NAME='SCONN3_212H9103GBR1';
      BODY_NAME='SCONN3_212H9103GBR1';
      PHYS_DES_PREFIX='J';
      CLASS='IO';
      STANDARD='';
      LIFECYCLE='';
      JEDEC_TYPE='HEADER1X3SXE_H367';
      DESCRIPTION='CONN SMD HEADER 3P 1R MS(P2.54,H9.3)';
      MANUFTR='PRX';
      MANUF_PN='212-H91-03GBR1';
      RD_CMPLS_LVL='EP(V1)';
      CMPLS_LVL='EP(V1)';
      DIP_SMD='';
      FROM_PJ='S5C-HOWARD';
      DATA='PRX_212-H91-03GBR1.pdf';
      FP_ECN='212-H91-03GBR1.msg';
      EE_CHECK_LIST='';
      CREATOR='';
      CREATEDAY='20200131';
      PSL='';
      STATUS='';
      ESD_CDM='NA';
      ESD_HBM='NA';
      ESD_MM='NA';
      MSD='NA';
      PIN_LENGTH_LONG_PIN='0 MILS';
      PIN_LENGTH_SHORT_PIN='0 MILS';
      PARENT_PART_TYPE='SCONN3_212H9103GBR1';
      PARENT_PPT='SCONN3_212H9103GBR1';
      PARENT_PPT_PART='SCONN3_212H9103GBR1-SCONN3_212-H91-03GBR1,SMLF,EMPTY,DFHD03MS161';
  end_body;
end_primitive;
primitive 'SCONN67_NASA0S6730TS67-SCONN67A';
  pin
    '2':
      PIN_NUMBER='(2)';
      BIDIRECTIONAL='TRUE';
      INPUT_LOAD='(-0.01,0.01)';
      OUTPUT_LOAD='(1.0,-1.0)';
      PINUSE='BI';
    '4':
      PIN_NUMBER='(4)';
      BIDIRECTIONAL='TRUE';
      INPUT_LOAD='(-0.01,0.01)';
      OUTPUT_LOAD='(1.0,-1.0)';
      PINUSE='BI';
    '6':
      PIN_NUMBER='(6)';
      BIDIRECTIONAL='TRUE';
      INPUT_LOAD='(-0.01,0.01)';
      OUTPUT_LOAD='(1.0,-1.0)';
      PINUSE='BI';
    '16':
      PIN_NUMBER='(16)';
      BIDIRECTIONAL='TRUE';
      INPUT_LOAD='(-0.01,0.01)';
      OUTPUT_LOAD='(1.0,-1.0)';
      PINUSE='BI';
    '18':
      PIN_NUMBER='(18)';
      BIDIRECTIONAL='TRUE';
      INPUT_LOAD='(-0.01,0.01)';
      OUTPUT_LOAD='(1.0,-1.0)';
      PINUSE='BI';
    '20':
      PIN_NUMBER='(20)';
      BIDIRECTIONAL='TRUE';
      INPUT_LOAD='(-0.01,0.01)';
      OUTPUT_LOAD='(1.0,-1.0)';
      PINUSE='BI';
    '22':
      PIN_NUMBER='(22)';
      BIDIRECTIONAL='TRUE';
      INPUT_LOAD='(-0.01,0.01)';
      OUTPUT_LOAD='(1.0,-1.0)';
      PINUSE='BI';
    '24':
      PIN_NUMBER='(24)';
      BIDIRECTIONAL='TRUE';
      INPUT_LOAD='(-0.01,0.01)';
      OUTPUT_LOAD='(1.0,-1.0)';
      PINUSE='BI';
    '26':
      PIN_NUMBER='(26)';
      BIDIRECTIONAL='TRUE';
      INPUT_LOAD='(-0.01,0.01)';
      OUTPUT_LOAD='(1.0,-1.0)';
      PINUSE='BI';
    '28':
      PIN_NUMBER='(28)';
      BIDIRECTIONAL='TRUE';
      INPUT_LOAD='(-0.01,0.01)';
      OUTPUT_LOAD='(1.0,-1.0)';
      PINUSE='BI';
    '30':
      PIN_NUMBER='(30)';
      BIDIRECTIONAL='TRUE';
      INPUT_LOAD='(-0.01,0.01)';
      OUTPUT_LOAD='(1.0,-1.0)';
      PINUSE='BI';
    '32':
      PIN_NUMBER='(32)';
      BIDIRECTIONAL='TRUE';
      INPUT_LOAD='(-0.01,0.01)';
      OUTPUT_LOAD='(1.0,-1.0)';
      PINUSE='BI';
    '34':
      PIN_NUMBER='(34)';
      BIDIRECTIONAL='TRUE';
      INPUT_LOAD='(-0.01,0.01)';
      OUTPUT_LOAD='(1.0,-1.0)';
      PINUSE='BI';
    '36':
      PIN_NUMBER='(36)';
      BIDIRECTIONAL='TRUE';
      INPUT_LOAD='(-0.01,0.01)';
      OUTPUT_LOAD='(1.0,-1.0)';
      PINUSE='BI';
    '38':
      PIN_NUMBER='(38)';
      BIDIRECTIONAL='TRUE';
      INPUT_LOAD='(-0.01,0.01)';
      OUTPUT_LOAD='(1.0,-1.0)';
      PINUSE='BI';
    '40':
      PIN_NUMBER='(40)';
      BIDIRECTIONAL='TRUE';
      INPUT_LOAD='(-0.01,0.01)';
      OUTPUT_LOAD='(1.0,-1.0)';
      PINUSE='BI';
    '42':
      PIN_NUMBER='(42)';
      BIDIRECTIONAL='TRUE';
      INPUT_LOAD='(-0.01,0.01)';
      OUTPUT_LOAD='(1.0,-1.0)';
      PINUSE='BI';
    '44':
      PIN_NUMBER='(44)';
      BIDIRECTIONAL='TRUE';
      INPUT_LOAD='(-0.01,0.01)';
      OUTPUT_LOAD='(1.0,-1.0)';
      PINUSE='BI';
    '46':
      PIN_NUMBER='(46)';
      BIDIRECTIONAL='TRUE';
      INPUT_LOAD='(-0.01,0.01)';
      OUTPUT_LOAD='(1.0,-1.0)';
      PINUSE='BI';
    '48':
      PIN_NUMBER='(48)';
      BIDIRECTIONAL='TRUE';
      INPUT_LOAD='(-0.01,0.01)';
      OUTPUT_LOAD='(1.0,-1.0)';
      PINUSE='BI';
    '50':
      PIN_NUMBER='(50)';
      BIDIRECTIONAL='TRUE';
      INPUT_LOAD='(-0.01,0.01)';
      OUTPUT_LOAD='(1.0,-1.0)';
      PINUSE='BI';
    '52':
      PIN_NUMBER='(52)';
      BIDIRECTIONAL='TRUE';
      INPUT_LOAD='(-0.01,0.01)';
      OUTPUT_LOAD='(1.0,-1.0)';
      PINUSE='BI';
    '54':
      PIN_NUMBER='(54)';
      BIDIRECTIONAL='TRUE';
      INPUT_LOAD='(-0.01,0.01)';
      OUTPUT_LOAD='(1.0,-1.0)';
      PINUSE='BI';
    '56':
      PIN_NUMBER='(56)';
      BIDIRECTIONAL='TRUE';
      INPUT_LOAD='(-0.01,0.01)';
      OUTPUT_LOAD='(1.0,-1.0)';
      PINUSE='BI';
    '58':
      PIN_NUMBER='(58)';
      BIDIRECTIONAL='TRUE';
      INPUT_LOAD='(-0.01,0.01)';
      OUTPUT_LOAD='(1.0,-1.0)';
      PINUSE='BI';
    '60':
      PIN_NUMBER='(60)';
      BIDIRECTIONAL='TRUE';
      INPUT_LOAD='(-0.01,0.01)';
      OUTPUT_LOAD='(1.0,-1.0)';
      PINUSE='BI';
    '62':
      PIN_NUMBER='(62)';
      BIDIRECTIONAL='TRUE';
      INPUT_LOAD='(-0.01,0.01)';
      OUTPUT_LOAD='(1.0,-1.0)';
      PINUSE='BI';
    '64':
      PIN_NUMBER='(64)';
      BIDIRECTIONAL='TRUE';
      INPUT_LOAD='(-0.01,0.01)';
      OUTPUT_LOAD='(1.0,-1.0)';
      PINUSE='BI';
    '66':
      PIN_NUMBER='(66)';
      BIDIRECTIONAL='TRUE';
      INPUT_LOAD='(-0.01,0.01)';
      OUTPUT_LOAD='(1.0,-1.0)';
      PINUSE='BI';
    '68':
      PIN_NUMBER='(68)';
      BIDIRECTIONAL='TRUE';
      INPUT_LOAD='(-0.01,0.01)';
      OUTPUT_LOAD='(1.0,-1.0)';
      PINUSE='BI';
    '70':
      PIN_NUMBER='(70)';
      BIDIRECTIONAL='TRUE';
      INPUT_LOAD='(-0.01,0.01)';
      OUTPUT_LOAD='(1.0,-1.0)';
      PINUSE='BI';
    '72':
      PIN_NUMBER='(72)';
      BIDIRECTIONAL='TRUE';
      INPUT_LOAD='(-0.01,0.01)';
      OUTPUT_LOAD='(1.0,-1.0)';
      PINUSE='BI';
    '74':
      PIN_NUMBER='(74)';
      BIDIRECTIONAL='TRUE';
      INPUT_LOAD='(-0.01,0.01)';
      OUTPUT_LOAD='(1.0,-1.0)';
      PINUSE='BI';
    '1':
      PIN_NUMBER='(1)';
      BIDIRECTIONAL='TRUE';
      INPUT_LOAD='(-0.01,0.01)';
      OUTPUT_LOAD='(1.0,-1.0)';
      PINUSE='BI';
    '3':
      PIN_NUMBER='(3)';
      BIDIRECTIONAL='TRUE';
      INPUT_LOAD='(-0.01,0.01)';
      OUTPUT_LOAD='(1.0,-1.0)';
      PINUSE='BI';
    '5':
      PIN_NUMBER='(5)';
      BIDIRECTIONAL='TRUE';
      INPUT_LOAD='(-0.01,0.01)';
      OUTPUT_LOAD='(1.0,-1.0)';
      PINUSE='BI';
    '7':
      PIN_NUMBER='(7)';
      BIDIRECTIONAL='TRUE';
      INPUT_LOAD='(-0.01,0.01)';
      OUTPUT_LOAD='(1.0,-1.0)';
      PINUSE='BI';
    '17':
      PIN_NUMBER='(17)';
      BIDIRECTIONAL='TRUE';
      INPUT_LOAD='(-0.01,0.01)';
      OUTPUT_LOAD='(1.0,-1.0)';
      PINUSE='BI';
    '19':
      PIN_NUMBER='(19)';
      BIDIRECTIONAL='TRUE';
      INPUT_LOAD='(-0.01,0.01)';
      OUTPUT_LOAD='(1.0,-1.0)';
      PINUSE='BI';
    '21':
      PIN_NUMBER='(21)';
      BIDIRECTIONAL='TRUE';
      INPUT_LOAD='(-0.01,0.01)';
      OUTPUT_LOAD='(1.0,-1.0)';
      PINUSE='BI';
    '23':
      PIN_NUMBER='(23)';
      BIDIRECTIONAL='TRUE';
      INPUT_LOAD='(-0.01,0.01)';
      OUTPUT_LOAD='(1.0,-1.0)';
      PINUSE='BI';
    '25':
      PIN_NUMBER='(25)';
      BIDIRECTIONAL='TRUE';
      INPUT_LOAD='(-0.01,0.01)';
      OUTPUT_LOAD='(1.0,-1.0)';
      PINUSE='BI';
    '27':
      PIN_NUMBER='(27)';
      BIDIRECTIONAL='TRUE';
      INPUT_LOAD='(-0.01,0.01)';
      OUTPUT_LOAD='(1.0,-1.0)';
      PINUSE='BI';
    '29':
      PIN_NUMBER='(29)';
      BIDIRECTIONAL='TRUE';
      INPUT_LOAD='(-0.01,0.01)';
      OUTPUT_LOAD='(1.0,-1.0)';
      PINUSE='BI';
    '31':
      PIN_NUMBER='(31)';
      BIDIRECTIONAL='TRUE';
      INPUT_LOAD='(-0.01,0.01)';
      OUTPUT_LOAD='(1.0,-1.0)';
      PINUSE='BI';
    '33':
      PIN_NUMBER='(33)';
      BIDIRECTIONAL='TRUE';
      INPUT_LOAD='(-0.01,0.01)';
      OUTPUT_LOAD='(1.0,-1.0)';
      PINUSE='BI';
    '35':
      PIN_NUMBER='(35)';
      BIDIRECTIONAL='TRUE';
      INPUT_LOAD='(-0.01,0.01)';
      OUTPUT_LOAD='(1.0,-1.0)';
      PINUSE='BI';
    '37':
      PIN_NUMBER='(37)';
      BIDIRECTIONAL='TRUE';
      INPUT_LOAD='(-0.01,0.01)';
      OUTPUT_LOAD='(1.0,-1.0)';
      PINUSE='BI';
    '39':
      PIN_NUMBER='(39)';
      BIDIRECTIONAL='TRUE';
      INPUT_LOAD='(-0.01,0.01)';
      OUTPUT_LOAD='(1.0,-1.0)';
      PINUSE='BI';
    '41':
      PIN_NUMBER='(41)';
      BIDIRECTIONAL='TRUE';
      INPUT_LOAD='(-0.01,0.01)';
      OUTPUT_LOAD='(1.0,-1.0)';
      PINUSE='BI';
    '43':
      PIN_NUMBER='(43)';
      BIDIRECTIONAL='TRUE';
      INPUT_LOAD='(-0.01,0.01)';
      OUTPUT_LOAD='(1.0,-1.0)';
      PINUSE='BI';
    '45':
      PIN_NUMBER='(45)';
      BIDIRECTIONAL='TRUE';
      INPUT_LOAD='(-0.01,0.01)';
      OUTPUT_LOAD='(1.0,-1.0)';
      PINUSE='BI';
    '47':
      PIN_NUMBER='(47)';
      BIDIRECTIONAL='TRUE';
      INPUT_LOAD='(-0.01,0.01)';
      OUTPUT_LOAD='(1.0,-1.0)';
      PINUSE='BI';
    '49':
      PIN_NUMBER='(49)';
      BIDIRECTIONAL='TRUE';
      INPUT_LOAD='(-0.01,0.01)';
      OUTPUT_LOAD='(1.0,-1.0)';
      PINUSE='BI';
    '51':
      PIN_NUMBER='(51)';
      BIDIRECTIONAL='TRUE';
      INPUT_LOAD='(-0.01,0.01)';
      OUTPUT_LOAD='(1.0,-1.0)';
      PINUSE='BI';
    '53':
      PIN_NUMBER='(53)';
      BIDIRECTIONAL='TRUE';
      INPUT_LOAD='(-0.01,0.01)';
      OUTPUT_LOAD='(1.0,-1.0)';
      PINUSE='BI';
    '55':
      PIN_NUMBER='(55)';
      BIDIRECTIONAL='TRUE';
      INPUT_LOAD='(-0.01,0.01)';
      OUTPUT_LOAD='(1.0,-1.0)';
      PINUSE='BI';
    '57':
      PIN_NUMBER='(57)';
      BIDIRECTIONAL='TRUE';
      INPUT_LOAD='(-0.01,0.01)';
      OUTPUT_LOAD='(1.0,-1.0)';
      PINUSE='BI';
    '59':
      PIN_NUMBER='(59)';
      BIDIRECTIONAL='TRUE';
      INPUT_LOAD='(-0.01,0.01)';
      OUTPUT_LOAD='(1.0,-1.0)';
      PINUSE='BI';
    '61':
      PIN_NUMBER='(61)';
      BIDIRECTIONAL='TRUE';
      INPUT_LOAD='(-0.01,0.01)';
      OUTPUT_LOAD='(1.0,-1.0)';
      PINUSE='BI';
    '63':
      PIN_NUMBER='(63)';
      BIDIRECTIONAL='TRUE';
      INPUT_LOAD='(-0.01,0.01)';
      OUTPUT_LOAD='(1.0,-1.0)';
      PINUSE='BI';
    '65':
      PIN_NUMBER='(65)';
      BIDIRECTIONAL='TRUE';
      INPUT_LOAD='(-0.01,0.01)';
      OUTPUT_LOAD='(1.0,-1.0)';
      PINUSE='BI';
    '67':
      PIN_NUMBER='(67)';
      BIDIRECTIONAL='TRUE';
      INPUT_LOAD='(-0.01,0.01)';
      OUTPUT_LOAD='(1.0,-1.0)';
      PINUSE='BI';
    '69':
      PIN_NUMBER='(69)';
      BIDIRECTIONAL='TRUE';
      INPUT_LOAD='(-0.01,0.01)';
      OUTPUT_LOAD='(1.0,-1.0)';
      PINUSE='BI';
    '71':
      PIN_NUMBER='(71)';
      BIDIRECTIONAL='TRUE';
      INPUT_LOAD='(-0.01,0.01)';
      OUTPUT_LOAD='(1.0,-1.0)';
      PINUSE='BI';
    '73':
      PIN_NUMBER='(73)';
      BIDIRECTIONAL='TRUE';
      INPUT_LOAD='(-0.01,0.01)';
      OUTPUT_LOAD='(1.0,-1.0)';
      PINUSE='BI';
    '75':
      PIN_NUMBER='(75)';
      BIDIRECTIONAL='TRUE';
      INPUT_LOAD='(-0.01,0.01)';
      OUTPUT_LOAD='(1.0,-1.0)';
      PINUSE='BI';
    'G1':
      PIN_NUMBER='(G1)';
      PINUSE='POWER';
      NO_LOAD_CHECK='Both';
      NO_IO_CHECK='Both';
      NO_ASSERT_CHECK='TRUE';
      NO_DIR_CHECK='TRUE';
      ALLOW_CONNECT='TRUE';
    'G2':
      PIN_NUMBER='(G2)';
      PINUSE='POWER';
      NO_LOAD_CHECK='Both';
      NO_IO_CHECK='Both';
      NO_ASSERT_CHECK='TRUE';
      NO_DIR_CHECK='TRUE';
      ALLOW_CONNECT='TRUE';
  end_pin;
  body
      PART_NAME='SCONN67_NASA0S6730TS67';
      BODY_NAME='SCONN67_NASA0S6730TS67';
      PHYS_DES_PREFIX='J';
      CLASS='IO';
      NC_PINS='(H1,H2)';
      STANDARD='';
      LIFECYCLE='';
      JEDEC_TYPE='CON_F67S2H2D2S_P0-5W7-55_LUVXM';
      DESCRIPTION='CONN SMD HOUSING 75P 2R FR(P0.5,H6.7)';
      MANUFTR='LTK';
      MANUF_PN='NASA0-S6730-TS67';
      RD_CMPLS_LVL='EP(V1)';
      CMPLS_LVL='';
      DIP_SMD='';
      FROM_PJ='F0G-BELL';
      DATA='LTK_NASA0-S6730-TS67.pdf';
      FP_ECN='NASA0-S6730-TS67.msg';
      EE_CHECK_LIST='';
      CREATOR='';
      CREATEDAY='20191002';
      PSL='';
      STATUS='';
      ESD_CDM='NA';
      ESD_HBM='NA';
      ESD_MM='NA';
      MSD='NA';
      PIN_LENGTH_LONG_PIN='30 MILS';
      PIN_LENGTH_SHORT_PIN='30 MILS';
      PARENT_PART_TYPE='SCONN67_NASA0S6730TS67';
      PARENT_PPT='SCONN67_NASA0S6730TS67';
      PARENT_PPT_PART='SCONN67_NASA0S6730TS67-SCONN67_NASA0-S6730-TS67,SMLF,IO,DFHS75FR133';
  end_body;
end_primitive;
primitive 'SN74LVC1G07DCKR-SN74LVC1G07DCKA';
  pin
    'VCC':
      PIN_NUMBER='(5)';
      PINUSE='POWER';
      NO_LOAD_CHECK='Both';
      NO_IO_CHECK='Both';
      NO_ASSERT_CHECK='TRUE';
      NO_DIR_CHECK='TRUE';
      ALLOW_CONNECT='TRUE';
    'A':
      PIN_NUMBER='(2)';
      INPUT_LOAD='(-0.01,0.01)';
      PINUSE='IN';
    'GND':
      PIN_NUMBER='(3)';
      PINUSE='POWER';
      NO_LOAD_CHECK='Both';
      NO_IO_CHECK='Both';
      NO_ASSERT_CHECK='TRUE';
      NO_DIR_CHECK='TRUE';
      ALLOW_CONNECT='TRUE';
    'Y':
      PIN_NUMBER='(4)';
      OUTPUT_TYPE='(OC,AND)';
      OUTPUT_LOAD='(1.0,*)';
      PINUSE='OCA';
    'NC1':
      PIN_NUMBER='(1)';
      OUTPUT_TYPE='(TS,TS)';
      INPUT_LOAD='(-0.01,0.01)';
      OUTPUT_LOAD='(1.0,-1.0)';
      PINUSE='TRI';
  end_pin;
  body
      PART_NAME='SN74LVC1G07DCKR';
      BODY_NAME='SN74LVC1G07DCKR';
      PHYS_DES_PREFIX='U';
      CLASS='IC';
      STANDARD='';
      LIFECYCLE='';
      JEDEC_TYPE='SC70-5XB';
      DESCRIPTION='IC OTHER(5P)SN74LVC1G07DCKR(SOT)';
      MANUFTR='TIC';
      MANUF_PN='SN74LVC1G07DCKR';
      RD_CMPLS_LVL='EP(V1)';
      CMPLS_LVL='EP(V1)';
      FROM_PJ='S50-STEVE';
      DIP_SMD='';
      DATA='TIC_SN74LVC1G07DCKR.pdf';
      EE_CHECK_LIST='';
      FP_ECN='';
      PSL='';
      CREATOR='';
      STATUS='';
      MSD='';
      ESD_CDM='';
      ESD_HBM='';
      ESD_MM='';
      PIN_LENGTH_SHORT_PIN='';
      PIN_LENGTH_LONG_PIN='';
      CREATEDAY='20100429';
      PARENT_PART_TYPE='SN74LVC1G07DCKR';
      PARENT_PPT='SN74LVC1G07DCKR';
      PARENT_PPT_PART='SN74LVC1G07DCKR-SN74LVC1G07DCKR,SMLF,IC,AL1G0007016';
  end_body;
end_primitive;
primitive 'SN74LVC1G14DCKR_SMLF-IC,SN74LVA';
  pin
    'A':
      PIN_NUMBER='(2)';
      INPUT_LOAD='(-0.01,0.01)';
      PINUSE='IN';
    'Y':
      PIN_NUMBER='(4)';
      OUTPUT_LOAD='(1.0,*)';
      OUTPUT_TYPE='(OC,AND)';
      PINUSE='OCA';
    'NC':
      PIN_NUMBER='(1)';
      INPUT_LOAD='(-0.01,0.01)';
      OUTPUT_LOAD='(1.0,-1.0)';
      OUTPUT_TYPE='(TS,TS)';
      PINUSE='TRI';
    'VCC':
      PIN_NUMBER='(5)';
      PINUSE='POWER';
    'GND':
      PIN_NUMBER='(3)';
      PINUSE='POWER';
  end_pin;
  body
      CLASS='IC';
      PART_NAME='SN74LVC1G14DCKR';
      PHYS_DES_PREFIX='U';
      STANDARD='';
      LIFECYCLE='';
      JEDEC_TYPE='SC70-5';
      DESCRIPTION='IC(5P) SN74LVC1G14DCKR(SC70)';
      HEIGHT='0.044IN';
      COMPONENT_TYPE='SMALLSMT';
      LEAD_LENGTH='';
      DFM_EXCLUSION='';
      LPID='';
      DAY='20100623';
      PARENT_PART_TYPE='SN74LVC1G14DCKR';
      PARENT_PPT='SN74LVC1G14DCKR';
      PARENT_PPT_PART='SN74LVC1G14DCKR_SMLF-IC,SN74LVC1G14DCKR,AL001G14017';
  end_body;
end_primitive;
primitive 'SW_PUSHBUTTON4P_12_G34_H2-SW4SA';
  pin
    '1':
      PIN_NUMBER='(1)';
      BIDIRECTIONAL='TRUE';
      INPUT_LOAD='(-0.01,0.01)';
      OUTPUT_LOAD='(1.0,-1.0)';
      PINUSE='BI';
    '2':
      PIN_NUMBER='(2)';
      BIDIRECTIONAL='TRUE';
      INPUT_LOAD='(-0.01,0.01)';
      OUTPUT_LOAD='(1.0,-1.0)';
      PINUSE='BI';
    '3':
      PIN_NUMBER='(3)';
      BIDIRECTIONAL='TRUE';
      INPUT_LOAD='(-0.01,0.01)';
      OUTPUT_LOAD='(1.0,-1.0)';
      PINUSE='BI';
    '4':
      PIN_NUMBER='(4)';
      BIDIRECTIONAL='TRUE';
      INPUT_LOAD='(-0.01,0.01)';
      OUTPUT_LOAD='(1.0,-1.0)';
      PINUSE='BI';
  end_pin;
  body
      PART_NAME='SW_PUSHBUTTON4P_12_G34_H2';
      BODY_NAME='SW_PUSHBUTTON4P_12_G34_H2';
      PHYS_DES_PREFIX='SW';
      CLASS='IO';
      NC_PINS='(H1,H2)';
      STANDARD='';
      LIFECYCLE='';
      JEDEC_TYPE='SW4S_DTSAM63N';
      DESCRIPTION='SWITCH TACT DTSAM-63N/K-S-Q-T/R';
      MANUFTR='DIP';
      MANUF_PN='DTSAM-63N/K-S-Q-T/R';
      RD_CMPLS_LVL='EU(V1)';
      CMPLS_LVL='';
      DIP_SMD='';
      FROM_PJ='T2R-WADE';
      DATA='DIP_RD5P6AM_REVA.pdf';
      FP_ECN='';
      EE_CHECK_LIST='';
      PSL='';
      PREFERENCE='';
      CREATOR='';
      CREATEDAY='20140306';
      STATUS='';
      PARENT_PART_TYPE='SW_PUSHBUTTON4P_12_G34_H2';
      PARENT_PPT='SW_PUSHBUTTON4P_12_G34_H2';
      PARENT_PPT_PART='SW_PUSHBUTTON4P_12_G34_H2-SW4S_DTSAM-63N/K-S-Q-T/R,SMLF,MECH,DHPDTSAM601';
  end_body;
end_primitive;
primitive 'TDR_3P_TH2-EMPTY,N_A';
  pin
    'GND':
      PIN_NUMBER='(1)';
      PINUSE='UNSPEC';
      NO_LOAD_CHECK='BOTH';
      NO_IO_CHECK='BOTH';
      ALLOW_CONNECT='TRUE';
    'IO1':
      PIN_NUMBER='(2)';
      PINUSE='UNSPEC';
      NO_LOAD_CHECK='BOTH';
      NO_IO_CHECK='BOTH';
      ALLOW_CONNECT='TRUE';
    'IO2':
      PIN_NUMBER='(3)';
      PINUSE='UNSPEC';
      NO_LOAD_CHECK='BOTH';
      NO_IO_CHECK='BOTH';
      ALLOW_CONNECT='TRUE';
  end_pin;
  body
      PART_NAME='TDR_3P';
      BODY_NAME='TDR_3P';
      PHYS_DES_PREFIX='DB';
      CLASS='IO';
      STANDARD='';
      LIFECYCLE='';
      JEDEC_TYPE='TDR_3P_C85P67_141_100M_Q';
      ALT_SYMBOLS='(TDR_3P_C85P67_141_100M)';
      DESCRIPTION='(USE SYM_2)TDR 3PIN,2X141MIL 1X100MIL P2P';
      HEIGHT='0.00001 IN';
      COMPONENT_TYPE='PSEUDO';
      LPID='';
      SPEED_URL='';
      PARENT_PART_TYPE='TDR_3P_TH2';
      PARENT_PPT='TDR_3P';
      PARENT_PPT_PART='TDR_3P_TH2-EMPTY,N_A';
  end_body;
end_primitive;
primitive 'TPS3808G18DBVR-TPS3808G01DBVR,A';
  pin
    '#RESET':
      PIN_NUMBER='(1)';
      OUTPUT_LOAD='(1.0,-1.0)';
      PINUSE='OUT';
    'GND':
      PIN_NUMBER='(2)';
      PINUSE='POWER';
      NO_LOAD_CHECK='Both';
      NO_IO_CHECK='Both';
      NO_ASSERT_CHECK='TRUE';
      NO_DIR_CHECK='TRUE';
      ALLOW_CONNECT='TRUE';
    '#MR':
      PIN_NUMBER='(3)';
      INPUT_LOAD='(-0.01,0.01)';
      PINUSE='IN';
    'VDD':
      PIN_NUMBER='(6)';
      PINUSE='POWER';
      NO_LOAD_CHECK='Both';
      NO_IO_CHECK='Both';
      NO_ASSERT_CHECK='TRUE';
      NO_DIR_CHECK='TRUE';
      ALLOW_CONNECT='TRUE';
    'CT':
      PIN_NUMBER='(4)';
      INPUT_LOAD='(-0.01,0.01)';
      PINUSE='IN';
    'SENSE':
      PIN_NUMBER='(5)';
      PINUSE='POWER';
      NO_LOAD_CHECK='Both';
      NO_IO_CHECK='Both';
      NO_ASSERT_CHECK='TRUE';
      NO_DIR_CHECK='TRUE';
      ALLOW_CONNECT='TRUE';
  end_pin;
  body
      PART_NAME='TPS3808G18DBVR';
      BODY_NAME='TPS3808G18DBVR';
      PHYS_DES_PREFIX='U';
      CLASS='IC';
      JEDEC_TYPE='SOT23-6XD';
      DESCRIPTION='IC OTHER(6P)TPS3808G01DBVR(SOT23)';
      MANUFTR='TIC';
      MANUF_PN='TPS3808G01DBVR';
      RD_CMPLS_LVL='EP(V1)';
      CMPLS_LVL='EP(V1)';
      FROM_PJ='T2B-JHIH-RONG';
      DIP_SMD='';
      DATA='TPS3808_REV2008.pdf';
      EE_CHECK_LIST='';
      FP_ECN='';
      PSL='';
      LIFECYCLE='';
      CREATOR='';
      STANDARD='';
      CREATEDAY='20120327';
      STATUS='';
      PARENT_PART_TYPE='TPS3808G18DBVR';
      PARENT_PPT='TPS3808G18DBVR';
      PARENT_PPT_PART='TPS3808G18DBVR-TPS3808G01DBVR,SMLF,IC,AL003808005';
  end_body;
end_primitive;
primitive 'TP_TDR_4P_FTS_TH-TP_TDR_4P_DIPA';
  pin
    'P1':
      PIN_NUMBER='(2)';
      INPUT_LOAD='(-0.01,0.01)';
      OUTPUT_LOAD='(1.0,-1.0)';
      BIDIRECTIONAL='TRUE';
      PINUSE='BI';
    'P2':
      PIN_NUMBER='(3)';
      INPUT_LOAD='(-0.01,0.01)';
      OUTPUT_LOAD='(1.0,-1.0)';
      BIDIRECTIONAL='TRUE';
      PINUSE='BI';
    'S1':
      PIN_NUMBER='(1)';
      INPUT_LOAD='(-0.01,0.01)';
      OUTPUT_LOAD='(1.0,-1.0)';
      BIDIRECTIONAL='TRUE';
      PINUSE='BI';
    'S2':
      PIN_NUMBER='(4)';
      INPUT_LOAD='(-0.01,0.01)';
      OUTPUT_LOAD='(1.0,-1.0)';
      BIDIRECTIONAL='TRUE';
      PINUSE='BI';
  end_pin;
  body
      CLASS='IO';
      PART_NAME='TP_TDR_4P_FTS';
      PHYS_DES_PREFIX='X';
      STANDARD='';
      LIFECYCLE='';
      ENVCOMP='(Error)';
      JEDEC_TYPE='MPKT4_H025P0200';
      DESCRIPTION='DIFF_TEST_PAD DIP FOR FTS ONLY';
      HEIGHT='0.00001 IN';
      COMPONENT_TYPE='PSEUDO';
      LPID='';
      STATUS='???';
      RPL='???';
      AML='???';
      DAYS='20110210';
      PARENT_PART_TYPE='TP_TDR_4P_FTS';
      PARENT_PPT='TP_TDR_4P_FTS';
      PARENT_PPT_PART='TP_TDR_4P_FTS_TH-TP_TDR_4P_DIP,EMPTY,TP15';
  end_body;
end_primitive;
END.
